FILE_TYPE = MACRO_DRAWING;
SET COLOR_WIRE YELLOW;
SET COLOR_PROP MONO;
SET COLOR_DOT WHITE;
SET COLOR_ARC YELLOW;
SET COLOR_BODY GREEN;
SET COLOR_NOTE MONO;
SET PROP_DISPLAY VALUE;
SET PAGE_NUMBER P233;
FORCEADD CAP..1
(-8150 725);
FORCEPROP 1 LASTPIN (-8150 625) $PN 2
J 0
(-8140 605);
DISPLAY 0.617021 (-8140 605);
PAINT GREEN (-8140 605);
FORCEPROP 1 LAST MATERIAL X6S
J 0
(-8100 625);
DISPLAY 0.617021 (-8100 625);
PAINT SKYBLUE (-8100 625);
FORCEPROP 1 LAST TOLERANCE 20%
J 0
(-8100 675);
DISPLAY 0.617021 (-8100 675);
PAINT SKYBLUE (-8100 675);
FORCEPROP 1 LASTPIN (-8150 825) $PN 1
J 0
(-8140 805);
DISPLAY 0.617021 (-8140 805);
PAINT GREEN (-8140 805);
FORCEPROP 1 LAST PART_NUMBER E15431-001
J 0
(-8100 575);
DISPLAY 0.617021 (-8100 575);
PAINT BLUE (-8100 575);
FORCEPROP 1 LAST VALUE 10UF
J 0
(-8100 775);
DISPLAY 0.617021 (-8100 775);
PAINT SKYBLUE (-8100 775);
FORCEPROP 1 LAST LOCATION C7U4
J 0
(-8100 825);
DISPLAY 0.617021 (-8100 825);
PAINT AQUA (-8100 825);
FORCEPROP 1 LAST PACK_TYPE 0603LF
J 0
(-8100 525);
DISPLAY 0.617021 (-8100 525);
PAINT SKYBLUE (-8100 525);
FORCEPROP 1 LAST VOLTAGE 4V
J 0
(-8100 725);
DISPLAY 0.638298 (-8100 725);
PAINT SKYBLUE (-8100 725);
FORCEPROP 0 LAST GROUP PWR_MLCC_CAP
J 0
(-8094 462);
DISPLAY 0.638298 (-8094 462);
PAINT BROWN (-8094 462);
DISPLAY BOTH (-8094 462);
FORCEPROP 2 LAST CDS_LIB mstr_discrete
J 0
(-8150 725);
PAINT ORANGE (-8150 725);
DISPLAY INVISIBLE (-8150 725);
FORCEPROP 2 LAST BOM_COST MEM_VRD_PVPP_AB
J 0
(-8100 875);
PAINT MONO (-8100 875);
DISPLAY INVISIBLE (-8100 875);
FORCEPROP 2 LAST CDS_SEC 1
J 0
(-8100 925);
PAINT MONO (-8100 925);
DISPLAY INVISIBLE (-8100 925);
FORCEPROP 2 LAST $SEC 1
J 0
(-8100 925);
PAINT MONO (-8100 925);
DISPLAY INVISIBLE (-8100 925);
FORCEPROP 2 LAST CDS_LOCATION C7U4
J 0
(-8100 825);
DISPLAY 0.617021 (-8100 825);
PAINT AQUA (-8100 825);
DISPLAY INVISIBLE (-8100 825);
FORCEPROP 1 LAST PATH I109
J 0
(-8100 875);
DISPLAY 0.978723 (-8100 875);
PAINT WHITE (-8100 875);
DISPLAY INVISIBLE (-8100 875);
FORCEPROP 2 LAST ROOM PVPP_KLM_VR
J 0
(-8100 875);
PAINT MONO (-8100 875);
DISPLAY INVISIBLE (-8100 875);
FORCEADD PVPP_GHJ..1
(-8100 1000);
FORCEPROP 3 LASTPIN (-8100 950) SIG_NAME PVPP_GHJ\g
J 0
(-8090 960);
DISPLAY 0.659574 (-8090 960);
PAINT MONO (-8090 960);
DISPLAY INVISIBLE (-8090 960);
FORCEPROP 2 LAST ROOM PVPP_KLM_VR
J 0
(-7850 1100);
PAINT ORANGE (-7850 1100);
DISPLAY INVISIBLE (-7850 1100);
FORCEPROP 1 LAST PATH I110
J 0
(-8050 1025);
DISPLAY 0.872340 (-8050 1025);
PAINT AQUA (-8050 1025);
DISPLAY INVISIBLE (-8050 1025);
FORCEPROP 2 LAST BOM_COST MEM_VRD_PVPP_AB
J 0
(-8025 1100);
PAINT MONO (-8025 1100);
DISPLAY INVISIBLE (-8025 1100);
FORCEPROP 2 LAST CDS_LIB mstr_symbols
J 0
(-8100 1000);
PAINT ORANGE (-8100 1000);
DISPLAY INVISIBLE (-8100 1000);
FORCEPROP 1 LAST VOLTAGE 2.5V
J 0
(-8145 957);
DISPLAY 0.340426 (-8145 957);
PAINT SKYBLUE (-8145 957);
DISPLAY INVISIBLE (-8145 957);
FORCEPROP 1 LAST BODY_TYPE PLUMBING
J 0
(-8145 957);
DISPLAY 0.340426 (-8145 957);
PAINT GREEN (-8145 957);
DISPLAY INVISIBLE (-8145 957);
FORCEPROP 1 LAST HDL_POWER PVPP_GHJ
J 1
(-8100 1050);
DISPLAY 0.872340 (-8100 1050);
PAINT GREEN (-8100 1050);
DISPLAY INVISIBLE (-8100 1050);
FORCEADD CAP..1
(-7875 725);
FORCEPROP 1 LAST TOLERANCE 20%
J 0
(-7825 675);
DISPLAY 0.617021 (-7825 675);
PAINT SKYBLUE (-7825 675);
FORCEPROP 1 LAST PACK_TYPE 0603LF
J 0
(-7825 525);
DISPLAY 0.617021 (-7825 525);
PAINT SKYBLUE (-7825 525);
FORCEPROP 1 LAST VALUE 10UF
J 0
(-7825 775);
DISPLAY 0.617021 (-7825 775);
PAINT SKYBLUE (-7825 775);
FORCEPROP 1 LAST LOCATION C7U5
J 0
(-7825 825);
DISPLAY 0.617021 (-7825 825);
PAINT AQUA (-7825 825);
FORCEPROP 1 LASTPIN (-7875 825) $PN 1
J 0
(-7865 805);
DISPLAY 0.617021 (-7865 805);
PAINT GREEN (-7865 805);
FORCEPROP 1 LAST MATERIAL X6S
J 0
(-7825 625);
DISPLAY 0.617021 (-7825 625);
PAINT SKYBLUE (-7825 625);
FORCEPROP 1 LASTPIN (-7875 625) $PN 2
J 0
(-7865 605);
DISPLAY 0.617021 (-7865 605);
PAINT GREEN (-7865 605);
FORCEPROP 1 LAST PART_NUMBER E15431-001
J 0
(-7825 575);
DISPLAY 0.617021 (-7825 575);
PAINT BLUE (-7825 575);
FORCEPROP 1 LAST VOLTAGE 4V
J 0
(-7825 725);
DISPLAY 0.638298 (-7825 725);
PAINT SKYBLUE (-7825 725);
FORCEPROP 0 LAST GROUP PWR_MLCC_CAP
J 0
(-7819 412);
DISPLAY 0.638298 (-7819 412);
PAINT BROWN (-7819 412);
DISPLAY BOTH (-7819 412);
FORCEPROP 2 LAST BOM_COST MEM_VRD_PVPP_AB
J 0
(-7825 875);
PAINT MONO (-7825 875);
DISPLAY INVISIBLE (-7825 875);
FORCEPROP 2 LAST CDS_SEC 1
J 0
(-7825 925);
PAINT MONO (-7825 925);
DISPLAY INVISIBLE (-7825 925);
FORCEPROP 2 LAST $SEC 1
J 0
(-7825 925);
PAINT MONO (-7825 925);
DISPLAY INVISIBLE (-7825 925);
FORCEPROP 2 LAST CDS_LOCATION C7U5
J 0
(-7825 825);
DISPLAY 0.617021 (-7825 825);
PAINT AQUA (-7825 825);
DISPLAY INVISIBLE (-7825 825);
FORCEPROP 1 LAST PATH I111
J 0
(-7825 875);
DISPLAY 0.978723 (-7825 875);
PAINT WHITE (-7825 875);
DISPLAY INVISIBLE (-7825 875);
FORCEPROP 2 LAST ROOM PVPP_KLM_VR
J 0
(-7825 875);
PAINT MONO (-7825 875);
DISPLAY INVISIBLE (-7825 875);
FORCEPROP 2 LAST CDS_LIB mstr_discrete
J 0
(-7875 725);
PAINT ORANGE (-7875 725);
DISPLAY INVISIBLE (-7875 725);
FORCEADD CAP..1
(-7600 725);
FORCEPROP 1 LAST TOLERANCE 20%
J 0
(-7550 675);
DISPLAY 0.617021 (-7550 675);
PAINT SKYBLUE (-7550 675);
FORCEPROP 1 LAST LOCATION C7T2
J 0
(-7550 825);
DISPLAY 0.617021 (-7550 825);
PAINT AQUA (-7550 825);
FORCEPROP 1 LAST PART_NUMBER E15431-001
J 0
(-7550 575);
DISPLAY 0.617021 (-7550 575);
PAINT BLUE (-7550 575);
FORCEPROP 1 LAST VALUE 10UF
J 0
(-7550 775);
DISPLAY 0.617021 (-7550 775);
PAINT SKYBLUE (-7550 775);
FORCEPROP 1 LASTPIN (-7600 825) $PN 1
J 0
(-7590 805);
DISPLAY 0.617021 (-7590 805);
PAINT GREEN (-7590 805);
FORCEPROP 1 LAST MATERIAL X6S
J 0
(-7550 625);
DISPLAY 0.617021 (-7550 625);
PAINT SKYBLUE (-7550 625);
FORCEPROP 1 LASTPIN (-7600 625) $PN 2
J 0
(-7590 605);
DISPLAY 0.617021 (-7590 605);
PAINT GREEN (-7590 605);
FORCEPROP 1 LAST VOLTAGE 4V
J 0
(-7550 725);
DISPLAY 0.638298 (-7550 725);
PAINT SKYBLUE (-7550 725);
FORCEPROP 1 LAST PACK_TYPE 0603LF
J 0
(-7550 525);
DISPLAY 0.617021 (-7550 525);
PAINT SKYBLUE (-7550 525);
FORCEPROP 0 LAST GROUP PWR_MLCC_CAP
J 0
(-7544 462);
DISPLAY 0.638298 (-7544 462);
PAINT BROWN (-7544 462);
DISPLAY BOTH (-7544 462);
FORCEPROP 2 LAST BOM_COST MEM_VRD_PVPP_AB
J 0
(-7550 875);
PAINT MONO (-7550 875);
DISPLAY INVISIBLE (-7550 875);
FORCEPROP 2 LAST CDS_SEC 1
J 0
(-7550 925);
PAINT MONO (-7550 925);
DISPLAY INVISIBLE (-7550 925);
FORCEPROP 2 LAST $SEC 1
J 0
(-7550 925);
PAINT MONO (-7550 925);
DISPLAY INVISIBLE (-7550 925);
FORCEPROP 2 LAST CDS_LOCATION C7T2
J 0
(-7550 825);
DISPLAY 0.617021 (-7550 825);
PAINT AQUA (-7550 825);
DISPLAY INVISIBLE (-7550 825);
FORCEPROP 1 LAST PATH I112
J 0
(-7550 875);
DISPLAY 0.978723 (-7550 875);
PAINT WHITE (-7550 875);
DISPLAY INVISIBLE (-7550 875);
FORCEPROP 2 LAST ROOM PVPP_KLM_VR
J 0
(-7550 875);
PAINT MONO (-7550 875);
DISPLAY INVISIBLE (-7550 875);
FORCEPROP 2 LAST CDS_LIB mstr_discrete
J 0
(-7600 725);
PAINT ORANGE (-7600 725);
DISPLAY INVISIBLE (-7600 725);
FORCEADD CAP..1
(-7325 725);
FORCEPROP 1 LAST TOLERANCE 20%
J 0
(-7275 675);
DISPLAY 0.617021 (-7275 675);
PAINT SKYBLUE (-7275 675);
FORCEPROP 1 LASTPIN (-7325 625) $PN 2
J 0
(-7315 605);
DISPLAY 0.617021 (-7315 605);
PAINT GREEN (-7315 605);
FORCEPROP 1 LAST MATERIAL X6S
J 0
(-7275 625);
DISPLAY 0.617021 (-7275 625);
PAINT SKYBLUE (-7275 625);
FORCEPROP 1 LASTPIN (-7325 825) $PN 1
J 0
(-7315 805);
DISPLAY 0.617021 (-7315 805);
PAINT GREEN (-7315 805);
FORCEPROP 1 LAST VALUE 10UF
J 0
(-7275 775);
DISPLAY 0.617021 (-7275 775);
PAINT SKYBLUE (-7275 775);
FORCEPROP 1 LAST LOCATION C7T3
J 0
(-7275 825);
DISPLAY 0.617021 (-7275 825);
PAINT AQUA (-7275 825);
FORCEPROP 1 LAST VOLTAGE 4V
J 0
(-7275 725);
DISPLAY 0.638298 (-7275 725);
PAINT SKYBLUE (-7275 725);
FORCEPROP 1 LAST PACK_TYPE 0603LF
J 0
(-7275 525);
DISPLAY 0.617021 (-7275 525);
PAINT SKYBLUE (-7275 525);
FORCEPROP 1 LAST PART_NUMBER E15431-001
J 0
(-7275 575);
DISPLAY 0.617021 (-7275 575);
PAINT BLUE (-7275 575);
FORCEPROP 0 LAST GROUP PWR_MLCC_CAP
J 0
(-7269 412);
DISPLAY 0.638298 (-7269 412);
PAINT BROWN (-7269 412);
DISPLAY BOTH (-7269 412);
FORCEPROP 2 LAST CDS_LIB mstr_discrete
J 0
(-7325 725);
PAINT ORANGE (-7325 725);
DISPLAY INVISIBLE (-7325 725);
FORCEPROP 2 LAST ROOM PVPP_KLM_VR
J 0
(-7275 875);
PAINT MONO (-7275 875);
DISPLAY INVISIBLE (-7275 875);
FORCEPROP 1 LAST PATH I113
J 0
(-7275 875);
DISPLAY 0.978723 (-7275 875);
PAINT WHITE (-7275 875);
DISPLAY INVISIBLE (-7275 875);
FORCEPROP 2 LAST CDS_LOCATION C7T3
J 0
(-7275 825);
DISPLAY 0.617021 (-7275 825);
PAINT AQUA (-7275 825);
DISPLAY INVISIBLE (-7275 825);
FORCEPROP 2 LAST $SEC 1
J 0
(-7275 925);
PAINT MONO (-7275 925);
DISPLAY INVISIBLE (-7275 925);
FORCEPROP 2 LAST CDS_SEC 1
J 0
(-7275 925);
PAINT MONO (-7275 925);
DISPLAY INVISIBLE (-7275 925);
FORCEPROP 2 LAST BOM_COST MEM_VRD_PVPP_AB
J 0
(-7275 875);
PAINT MONO (-7275 875);
DISPLAY INVISIBLE (-7275 875);
FORCEADD CAP..1
(-7050 725);
FORCEPROP 1 LAST VALUE 10UF
J 0
(-7000 775);
DISPLAY 0.617021 (-7000 775);
PAINT SKYBLUE (-7000 775);
FORCEPROP 1 LAST TOLERANCE 20%
J 0
(-7000 675);
DISPLAY 0.617021 (-7000 675);
PAINT SKYBLUE (-7000 675);
FORCEPROP 1 LAST MATERIAL X6S
J 0
(-7000 625);
DISPLAY 0.617021 (-7000 625);
PAINT SKYBLUE (-7000 625);
FORCEPROP 1 LASTPIN (-7050 625) $PN 2
J 0
(-7040 605);
DISPLAY 0.617021 (-7040 605);
PAINT GREEN (-7040 605);
FORCEPROP 1 LAST LOCATION C7U6
J 0
(-7000 825);
DISPLAY 0.617021 (-7000 825);
PAINT AQUA (-7000 825);
FORCEPROP 1 LAST PART_NUMBER E15431-001
J 0
(-7000 575);
DISPLAY 0.617021 (-7000 575);
PAINT BLUE (-7000 575);
FORCEPROP 1 LAST PACK_TYPE 0603LF
J 0
(-7000 525);
DISPLAY 0.617021 (-7000 525);
PAINT SKYBLUE (-7000 525);
FORCEPROP 1 LASTPIN (-7050 825) $PN 1
J 0
(-7040 805);
DISPLAY 0.617021 (-7040 805);
PAINT GREEN (-7040 805);
FORCEPROP 1 LAST VOLTAGE 4V
J 0
(-7000 725);
DISPLAY 0.638298 (-7000 725);
PAINT SKYBLUE (-7000 725);
FORCEPROP 0 LAST GROUP PWR_MLCC_CAP
J 0
(-6994 462);
DISPLAY 0.638298 (-6994 462);
PAINT BROWN (-6994 462);
DISPLAY BOTH (-6994 462);
FORCEPROP 2 LAST BOM_COST MEM_VRD_PVPP_AB
J 0
(-7000 875);
PAINT MONO (-7000 875);
DISPLAY INVISIBLE (-7000 875);
FORCEPROP 2 LAST CDS_SEC 1
J 0
(-7000 925);
PAINT MONO (-7000 925);
DISPLAY INVISIBLE (-7000 925);
FORCEPROP 2 LAST $SEC 1
J 0
(-7000 925);
PAINT MONO (-7000 925);
DISPLAY INVISIBLE (-7000 925);
FORCEPROP 2 LAST CDS_LOCATION C7U6
J 0
(-7000 825);
DISPLAY 0.617021 (-7000 825);
PAINT AQUA (-7000 825);
DISPLAY INVISIBLE (-7000 825);
FORCEPROP 1 LAST PATH I115
J 0
(-7000 875);
DISPLAY 0.978723 (-7000 875);
PAINT WHITE (-7000 875);
DISPLAY INVISIBLE (-7000 875);
FORCEPROP 2 LAST ROOM PVPP_KLM_VR
J 0
(-7000 875);
PAINT MONO (-7000 875);
DISPLAY INVISIBLE (-7000 875);
FORCEPROP 2 LAST CDS_LIB mstr_discrete
J 0
(-7050 725);
PAINT ORANGE (-7050 725);
DISPLAY INVISIBLE (-7050 725);
FORCEADD CAP..1
(-6750 725);
FORCEPROP 1 LASTPIN (-6750 825) $PN 1
J 0
(-6740 805);
DISPLAY 0.617021 (-6740 805);
PAINT GREEN (-6740 805);
FORCEPROP 1 LASTPIN (-6750 625) $PN 2
J 0
(-6740 605);
DISPLAY 0.617021 (-6740 605);
PAINT GREEN (-6740 605);
FORCEPROP 1 LAST PACK_TYPE 0603LF
J 0
(-6700 525);
DISPLAY 0.617021 (-6700 525);
PAINT SKYBLUE (-6700 525);
FORCEPROP 1 LAST PART_NUMBER E15431-001
J 0
(-6700 575);
DISPLAY 0.617021 (-6700 575);
PAINT BLUE (-6700 575);
FORCEPROP 1 LAST MATERIAL X6S
J 0
(-6700 625);
DISPLAY 0.617021 (-6700 625);
PAINT SKYBLUE (-6700 625);
FORCEPROP 1 LAST TOLERANCE 20%
J 0
(-6700 675);
DISPLAY 0.617021 (-6700 675);
PAINT SKYBLUE (-6700 675);
FORCEPROP 1 LAST VALUE 10UF
J 0
(-6700 775);
DISPLAY 0.617021 (-6700 775);
PAINT SKYBLUE (-6700 775);
FORCEPROP 1 LAST LOCATION C3F3
J 0
(-6700 825);
DISPLAY 0.617021 (-6700 825);
PAINT AQUA (-6700 825);
FORCEPROP 1 LAST VOLTAGE 4V
J 0
(-6700 725);
DISPLAY 0.638298 (-6700 725);
PAINT SKYBLUE (-6700 725);
FORCEPROP 0 LAST GROUP PWR_MLCC_CAP
J 0
(-6694 412);
DISPLAY 0.638298 (-6694 412);
PAINT BROWN (-6694 412);
DISPLAY BOTH (-6694 412);
FORCEPROP 2 LAST CDS_SEC 1
J 0
(-6700 925);
PAINT MONO (-6700 925);
DISPLAY INVISIBLE (-6700 925);
FORCEPROP 2 LAST $SEC 1
J 0
(-6700 925);
PAINT MONO (-6700 925);
DISPLAY INVISIBLE (-6700 925);
FORCEPROP 1 LAST PATH I116
J 0
(-6700 875);
DISPLAY 0.978723 (-6700 875);
PAINT WHITE (-6700 875);
DISPLAY INVISIBLE (-6700 875);
FORCEPROP 2 LAST BOM_COST MEM_VRD_PVPP_AB
J 0
(-6700 875);
PAINT MONO (-6700 875);
DISPLAY INVISIBLE (-6700 875);
FORCEPROP 2 LAST ROOM PVPP_KLM_VR
J 0
(-6700 875);
PAINT MONO (-6700 875);
DISPLAY INVISIBLE (-6700 875);
FORCEPROP 2 LAST CDS_LOCATION C3F3
J 0
(-6700 825);
DISPLAY 0.617021 (-6700 825);
PAINT AQUA (-6700 825);
DISPLAY INVISIBLE (-6700 825);
FORCEPROP 2 LAST CDS_LIB mstr_discrete
J 0
(-6750 725);
PAINT ORANGE (-6750 725);
DISPLAY INVISIBLE (-6750 725);
FORCEADD CAP..1
(-6475 725);
FORCEPROP 1 LAST LOCATION C3F4
J 0
(-6425 825);
DISPLAY 0.617021 (-6425 825);
PAINT AQUA (-6425 825);
FORCEPROP 1 LAST TOLERANCE 20%
J 0
(-6425 675);
DISPLAY 0.617021 (-6425 675);
PAINT SKYBLUE (-6425 675);
FORCEPROP 1 LAST PART_NUMBER E15431-001
J 0
(-6425 575);
DISPLAY 0.617021 (-6425 575);
PAINT BLUE (-6425 575);
FORCEPROP 1 LAST VALUE 10UF
J 0
(-6425 775);
DISPLAY 0.617021 (-6425 775);
PAINT SKYBLUE (-6425 775);
FORCEPROP 1 LAST MATERIAL X6S
J 0
(-6425 625);
DISPLAY 0.617021 (-6425 625);
PAINT SKYBLUE (-6425 625);
FORCEPROP 1 LASTPIN (-6475 825) $PN 1
J 0
(-6465 805);
DISPLAY 0.617021 (-6465 805);
PAINT GREEN (-6465 805);
FORCEPROP 1 LASTPIN (-6475 625) $PN 2
J 0
(-6465 605);
DISPLAY 0.617021 (-6465 605);
PAINT GREEN (-6465 605);
FORCEPROP 1 LAST VOLTAGE 4V
J 0
(-6425 725);
DISPLAY 0.638298 (-6425 725);
PAINT SKYBLUE (-6425 725);
FORCEPROP 1 LAST PACK_TYPE 0603LF
J 0
(-6425 525);
DISPLAY 0.617021 (-6425 525);
PAINT SKYBLUE (-6425 525);
FORCEPROP 0 LAST GROUP PWR_MLCC_CAP
J 0
(-6419 462);
DISPLAY 0.638298 (-6419 462);
PAINT BROWN (-6419 462);
DISPLAY BOTH (-6419 462);
FORCEPROP 2 LAST CDS_SEC 1
J 0
(-6425 925);
PAINT MONO (-6425 925);
DISPLAY INVISIBLE (-6425 925);
FORCEPROP 2 LAST $SEC 1
J 0
(-6425 925);
PAINT MONO (-6425 925);
DISPLAY INVISIBLE (-6425 925);
FORCEPROP 1 LAST PATH I117
J 0
(-6425 875);
DISPLAY 0.978723 (-6425 875);
PAINT WHITE (-6425 875);
DISPLAY INVISIBLE (-6425 875);
FORCEPROP 2 LAST BOM_COST MEM_VRD_PVPP_AB
J 0
(-6425 875);
PAINT MONO (-6425 875);
DISPLAY INVISIBLE (-6425 875);
FORCEPROP 2 LAST ROOM PVPP_KLM_VR
J 0
(-6425 875);
PAINT MONO (-6425 875);
DISPLAY INVISIBLE (-6425 875);
FORCEPROP 2 LAST CDS_LOCATION C3F4
J 0
(-6425 825);
DISPLAY 0.617021 (-6425 825);
PAINT AQUA (-6425 825);
DISPLAY INVISIBLE (-6425 825);
FORCEPROP 2 LAST CDS_LIB mstr_discrete
J 0
(-6475 725);
PAINT MONO (-6475 725);
DISPLAY INVISIBLE (-6475 725);
FORCEADD CAP..1
(-6175 725);
FORCEPROP 1 LAST TOLERANCE 20%
J 0
(-6125 675);
DISPLAY 0.617021 (-6125 675);
PAINT SKYBLUE (-6125 675);
FORCEPROP 1 LAST PART_NUMBER E15431-001
J 0
(-6125 575);
DISPLAY 0.617021 (-6125 575);
PAINT BLUE (-6125 575);
FORCEPROP 1 LAST LOCATION C3G3
J 0
(-6125 825);
DISPLAY 0.617021 (-6125 825);
PAINT AQUA (-6125 825);
FORCEPROP 1 LAST VALUE 10UF
J 0
(-6125 775);
DISPLAY 0.617021 (-6125 775);
PAINT SKYBLUE (-6125 775);
FORCEPROP 1 LAST MATERIAL X6S
J 0
(-6125 625);
DISPLAY 0.617021 (-6125 625);
PAINT SKYBLUE (-6125 625);
FORCEPROP 1 LASTPIN (-6175 625) $PN 2
J 0
(-6165 605);
DISPLAY 0.617021 (-6165 605);
PAINT GREEN (-6165 605);
FORCEPROP 1 LASTPIN (-6175 825) $PN 1
J 0
(-6165 805);
DISPLAY 0.617021 (-6165 805);
PAINT GREEN (-6165 805);
FORCEPROP 1 LAST VOLTAGE 4V
J 0
(-6125 725);
DISPLAY 0.638298 (-6125 725);
PAINT SKYBLUE (-6125 725);
FORCEPROP 1 LAST PACK_TYPE 0603LF
J 0
(-6125 525);
DISPLAY 0.617021 (-6125 525);
PAINT SKYBLUE (-6125 525);
FORCEPROP 0 LAST GROUP PWR_MLCC_CAP
J 0
(-6119 412);
DISPLAY 0.638298 (-6119 412);
PAINT BROWN (-6119 412);
DISPLAY BOTH (-6119 412);
FORCEPROP 2 LAST BOM_COST MEM_VRD_PVPP_AB
J 0
(-6125 875);
PAINT MONO (-6125 875);
DISPLAY INVISIBLE (-6125 875);
FORCEPROP 2 LAST CDS_SEC 1
J 0
(-6125 925);
PAINT MONO (-6125 925);
DISPLAY INVISIBLE (-6125 925);
FORCEPROP 2 LAST $SEC 1
J 0
(-6125 925);
PAINT MONO (-6125 925);
DISPLAY INVISIBLE (-6125 925);
FORCEPROP 2 LAST CDS_LOCATION C3G3
J 0
(-6125 825);
DISPLAY 0.617021 (-6125 825);
PAINT AQUA (-6125 825);
DISPLAY INVISIBLE (-6125 825);
FORCEPROP 1 LAST PATH I118
J 0
(-6125 875);
DISPLAY 0.978723 (-6125 875);
PAINT WHITE (-6125 875);
DISPLAY INVISIBLE (-6125 875);
FORCEPROP 2 LAST ROOM PVPP_KLM_VR
J 0
(-6125 875);
PAINT MONO (-6125 875);
DISPLAY INVISIBLE (-6125 875);
FORCEPROP 2 LAST CDS_LIB mstr_discrete
J 0
(-6175 725);
PAINT MONO (-6175 725);
DISPLAY INVISIBLE (-6175 725);
FORCEADD CAP..1
(-5875 725);
FORCEPROP 1 LAST PART_NUMBER E15431-001
J 0
(-5825 575);
DISPLAY 0.617021 (-5825 575);
PAINT BLUE (-5825 575);
FORCEPROP 1 LAST MATERIAL X6S
J 0
(-5825 625);
DISPLAY 0.617021 (-5825 625);
PAINT SKYBLUE (-5825 625);
FORCEPROP 1 LASTPIN (-5875 625) $PN 2
J 0
(-5865 605);
DISPLAY 0.617021 (-5865 605);
PAINT GREEN (-5865 605);
FORCEPROP 1 LAST TOLERANCE 20%
J 0
(-5825 675);
DISPLAY 0.617021 (-5825 675);
PAINT SKYBLUE (-5825 675);
FORCEPROP 1 LASTPIN (-5875 825) $PN 1
J 0
(-5865 805);
DISPLAY 0.617021 (-5865 805);
PAINT GREEN (-5865 805);
FORCEPROP 1 LAST VOLTAGE 4V
J 0
(-5825 725);
DISPLAY 0.638298 (-5825 725);
PAINT SKYBLUE (-5825 725);
FORCEPROP 1 LAST VALUE 10UF
J 0
(-5825 775);
DISPLAY 0.617021 (-5825 775);
PAINT SKYBLUE (-5825 775);
FORCEPROP 1 LAST LOCATION C3G7
J 0
(-5825 825);
DISPLAY 0.617021 (-5825 825);
PAINT AQUA (-5825 825);
FORCEPROP 1 LAST PACK_TYPE 0603LF
J 0
(-5825 525);
DISPLAY 0.617021 (-5825 525);
PAINT SKYBLUE (-5825 525);
FORCEPROP 0 LAST GROUP PWR_MLCC_CAP
J 0
(-5819 462);
DISPLAY 0.638298 (-5819 462);
PAINT BROWN (-5819 462);
DISPLAY BOTH (-5819 462);
FORCEPROP 2 LAST BOM_COST MEM_VRD_PVPP_AB
J 0
(-5825 875);
PAINT MONO (-5825 875);
DISPLAY INVISIBLE (-5825 875);
FORCEPROP 2 LAST CDS_SEC 1
J 0
(-5825 925);
PAINT MONO (-5825 925);
DISPLAY INVISIBLE (-5825 925);
FORCEPROP 2 LAST $SEC 1
J 0
(-5825 925);
PAINT MONO (-5825 925);
DISPLAY INVISIBLE (-5825 925);
FORCEPROP 2 LAST CDS_LOCATION C3G7
J 0
(-5825 825);
DISPLAY 0.617021 (-5825 825);
PAINT AQUA (-5825 825);
DISPLAY INVISIBLE (-5825 825);
FORCEPROP 1 LAST PATH I132
J 0
(-5825 875);
DISPLAY 0.978723 (-5825 875);
PAINT WHITE (-5825 875);
DISPLAY INVISIBLE (-5825 875);
FORCEPROP 2 LAST ROOM PVPP_KLM_VR
J 0
(-5825 875);
PAINT MONO (-5825 875);
DISPLAY INVISIBLE (-5825 875);
FORCEPROP 2 LAST CDS_LIB mstr_discrete
J 0
(-5875 725);
PAINT MONO (-5875 725);
DISPLAY INVISIBLE (-5875 725);
FORCEADD CAP..1
(-5600 725);
FORCEPROP 1 LAST VALUE 10UF
J 0
(-5550 775);
DISPLAY 0.617021 (-5550 775);
PAINT SKYBLUE (-5550 775);
FORCEPROP 1 LASTPIN (-5600 625) $PN 2
J 0
(-5590 605);
DISPLAY 0.617021 (-5590 605);
PAINT GREEN (-5590 605);
FORCEPROP 1 LASTPIN (-5600 825) $PN 1
J 0
(-5590 805);
DISPLAY 0.617021 (-5590 805);
PAINT GREEN (-5590 805);
FORCEPROP 1 LAST LOCATION C3G4
J 0
(-5550 825);
DISPLAY 0.617021 (-5550 825);
PAINT AQUA (-5550 825);
FORCEPROP 1 LAST VOLTAGE 4V
J 0
(-5550 725);
DISPLAY 0.638298 (-5550 725);
PAINT SKYBLUE (-5550 725);
FORCEPROP 1 LAST PACK_TYPE 0603LF
J 0
(-5550 525);
DISPLAY 0.617021 (-5550 525);
PAINT SKYBLUE (-5550 525);
FORCEPROP 1 LAST PART_NUMBER E15431-001
J 0
(-5550 575);
DISPLAY 0.617021 (-5550 575);
PAINT BLUE (-5550 575);
FORCEPROP 1 LAST MATERIAL X6S
J 0
(-5550 625);
DISPLAY 0.617021 (-5550 625);
PAINT SKYBLUE (-5550 625);
FORCEPROP 1 LAST TOLERANCE 20%
J 0
(-5550 675);
DISPLAY 0.617021 (-5550 675);
PAINT SKYBLUE (-5550 675);
FORCEPROP 0 LAST GROUP PWR_MLCC_CAP
J 0
(-5544 412);
DISPLAY 0.638298 (-5544 412);
PAINT BROWN (-5544 412);
DISPLAY BOTH (-5544 412);
FORCEPROP 2 LAST CDS_LIB mstr_discrete
J 0
(-5600 725);
PAINT MONO (-5600 725);
DISPLAY INVISIBLE (-5600 725);
FORCEPROP 1 LAST PATH I133
J 0
(-5550 875);
DISPLAY 0.978723 (-5550 875);
PAINT WHITE (-5550 875);
DISPLAY INVISIBLE (-5550 875);
FORCEPROP 2 LAST CDS_LOCATION C3G4
J 0
(-5550 825);
DISPLAY 0.617021 (-5550 825);
PAINT AQUA (-5550 825);
DISPLAY INVISIBLE (-5550 825);
FORCEPROP 2 LAST BOM_COST MEM_VRD_PVPP_AB
J 0
(-5550 875);
PAINT MONO (-5550 875);
DISPLAY INVISIBLE (-5550 875);
FORCEPROP 2 LAST ROOM PVPP_KLM_VR
J 0
(-5550 875);
PAINT MONO (-5550 875);
DISPLAY INVISIBLE (-5550 875);
FORCEPROP 2 LAST $SEC 1
J 0
(-5550 925);
PAINT MONO (-5550 925);
DISPLAY INVISIBLE (-5550 925);
FORCEPROP 2 LAST CDS_SEC 1
J 0
(-5550 925);
PAINT MONO (-5550 925);
DISPLAY INVISIBLE (-5550 925);
FORCEADD GND..1
(-8150 275);
FORCEPROP 3 LASTPIN (-8150 325) SIG_NAME GND\g
J 0
(-8140 335);
DISPLAY 0.659574 (-8140 335);
PAINT MONO (-8140 335);
DISPLAY INVISIBLE (-8140 335);
FORCEPROP 1 LAST HDL_POWER GND
J 0
(-8150 425);
DISPLAY 0.893617 (-8150 425);
PAINT GREEN (-8150 425);
DISPLAY INVISIBLE (-8150 425);
FORCEPROP 1 LAST BODY_TYPE PLUMBING
J 0
(-8195 232);
DISPLAY 0.340426 (-8195 232);
PAINT GREEN (-8195 232);
DISPLAY INVISIBLE (-8195 232);
FORCEPROP 2 LAST ROOM PVPP_KLM_VR
J 0
(-8700 350);
PAINT ORANGE (-8700 350);
DISPLAY INVISIBLE (-8700 350);
FORCEPROP 2 LAST CDS_LIB mstr_symbols
J 0
(-8150 275);
PAINT MONO (-8150 275);
DISPLAY INVISIBLE (-8150 275);
FORCEPROP 1 LAST VOLTAGE 0
J 0
(-8150 275);
PAINT SKYBLUE (-8150 275);
DISPLAY INVISIBLE (-8150 275);
FORCEPROP 2 LAST BOM_COST MEM_VRD_PVPP_AB
J 0
(-8475 350);
PAINT MONO (-8475 350);
DISPLAY INVISIBLE (-8475 350);
FORCEPROP 1 LAST PATH I134
J 0
(-8075 275);
DISPLAY 0.872340 (-8075 275);
PAINT AQUA (-8075 275);
DISPLAY INVISIBLE (-8075 275);
FORCEPROP 1 LAST SIZE 1B
J 0
(-8075 225);
DISPLAY 0.893617 (-8075 225);
PAINT GREEN (-8075 225);
DISPLAY INVISIBLE (-8075 225);
FORCEADD CAP..1
(-5325 725);
FORCEPROP 1 LAST TOLERANCE 20%
J 0
(-5275 675);
DISPLAY 0.617021 (-5275 675);
PAINT SKYBLUE (-5275 675);
FORCEPROP 1 LASTPIN (-5325 625) $PN 2
J 0
(-5315 605);
DISPLAY 0.617021 (-5315 605);
PAINT GREEN (-5315 605);
FORCEPROP 1 LAST MATERIAL X6S
J 0
(-5275 625);
DISPLAY 0.617021 (-5275 625);
PAINT SKYBLUE (-5275 625);
FORCEPROP 1 LASTPIN (-5325 825) $PN 1
J 0
(-5315 805);
DISPLAY 0.617021 (-5315 805);
PAINT GREEN (-5315 805);
FORCEPROP 1 LAST PART_NUMBER E15431-001
J 0
(-5275 575);
DISPLAY 0.617021 (-5275 575);
PAINT BLUE (-5275 575);
FORCEPROP 1 LAST LOCATION C3G8
J 0
(-5275 825);
DISPLAY 0.617021 (-5275 825);
PAINT AQUA (-5275 825);
FORCEPROP 1 LAST VOLTAGE 4V
J 0
(-5275 725);
DISPLAY 0.638298 (-5275 725);
PAINT SKYBLUE (-5275 725);
FORCEPROP 1 LAST VALUE 10UF
J 0
(-5275 775);
DISPLAY 0.617021 (-5275 775);
PAINT SKYBLUE (-5275 775);
FORCEPROP 1 LAST PACK_TYPE 0603LF
J 0
(-5275 525);
DISPLAY 0.617021 (-5275 525);
PAINT SKYBLUE (-5275 525);
FORCEPROP 0 LAST GROUP PWR_MLCC_CAP
J 0
(-5269 462);
DISPLAY 0.638298 (-5269 462);
PAINT BROWN (-5269 462);
DISPLAY BOTH (-5269 462);
FORCEPROP 2 LAST CDS_LIB mstr_discrete
J 0
(-5325 725);
PAINT MONO (-5325 725);
DISPLAY INVISIBLE (-5325 725);
FORCEPROP 2 LAST BOM_COST MEM_VRD_PVPP_AB
J 0
(-5275 875);
PAINT MONO (-5275 875);
DISPLAY INVISIBLE (-5275 875);
FORCEPROP 2 LAST CDS_LOCATION C3G8
J 0
(-5275 825);
DISPLAY 0.617021 (-5275 825);
PAINT AQUA (-5275 825);
DISPLAY INVISIBLE (-5275 825);
FORCEPROP 1 LAST PATH I135
J 0
(-5275 875);
DISPLAY 0.978723 (-5275 875);
PAINT WHITE (-5275 875);
DISPLAY INVISIBLE (-5275 875);
FORCEPROP 2 LAST ROOM PVPP_KLM_VR
J 0
(-5275 875);
PAINT MONO (-5275 875);
DISPLAY INVISIBLE (-5275 875);
FORCEPROP 2 LAST $SEC 1
J 0
(-5275 925);
PAINT MONO (-5275 925);
DISPLAY INVISIBLE (-5275 925);
FORCEPROP 2 LAST CDS_SEC 1
J 0
(-5275 925);
PAINT MONO (-5275 925);
DISPLAY INVISIBLE (-5275 925);
FORCEADD CAP..1
(-5000 725);
FORCEPROP 1 LASTPIN (-5000 625) $PN 2
J 0
(-4990 605);
DISPLAY 0.617021 (-4990 605);
PAINT GREEN (-4990 605);
FORCEPROP 1 LAST MATERIAL X6S
J 0
(-4950 625);
DISPLAY 0.617021 (-4950 625);
PAINT SKYBLUE (-4950 625);
FORCEPROP 1 LAST PART_NUMBER E15431-001
J 0
(-4950 575);
DISPLAY 0.617021 (-4950 575);
PAINT BLUE (-4950 575);
FORCEPROP 1 LAST PACK_TYPE 0603LF
J 0
(-4950 525);
DISPLAY 0.617021 (-4950 525);
PAINT SKYBLUE (-4950 525);
FORCEPROP 1 LAST LOCATION C7U3
J 0
(-4950 825);
DISPLAY 0.617021 (-4950 825);
PAINT AQUA (-4950 825);
FORCEPROP 1 LASTPIN (-5000 825) $PN 1
J 0
(-4990 805);
DISPLAY 0.617021 (-4990 805);
PAINT GREEN (-4990 805);
FORCEPROP 1 LAST VALUE 10UF
J 0
(-4950 775);
DISPLAY 0.617021 (-4950 775);
PAINT SKYBLUE (-4950 775);
FORCEPROP 0 LAST GROUP PWR_MLCC_CAP
J 0
(-4944 412);
DISPLAY 0.638298 (-4944 412);
PAINT BROWN (-4944 412);
DISPLAY BOTH (-4944 412);
FORCEPROP 1 LAST TOLERANCE 20%
J 0
(-4950 675);
DISPLAY 0.617021 (-4950 675);
PAINT SKYBLUE (-4950 675);
FORCEPROP 1 LAST VOLTAGE 4V
J 0
(-4950 725);
DISPLAY 0.638298 (-4950 725);
PAINT SKYBLUE (-4950 725);
FORCEPROP 2 LAST SEC 1
J 0
(-4930 945);
DISPLAY 0.680851 (-4930 945);
PAINT MONO (-4930 945);
DISPLAY INVISIBLE (-4930 945);
FORCEPROP 2 LAST BOM_COST MEM_VRD_PVPP_AB
J 0
(-4950 875);
PAINT MONO (-4950 875);
DISPLAY INVISIBLE (-4950 875);
FORCEPROP 2 LAST SEC_TYPE 0603LF
J 0
(-4930 945);
DISPLAY 1.021277 (-4930 945);
PAINT ORANGE (-4930 945);
DISPLAY INVISIBLE (-4930 945);
FORCEPROP 2 LAST ROOM PVPP_KLM_VR
J 0
(-4950 875);
PAINT MONO (-4950 875);
DISPLAY INVISIBLE (-4950 875);
FORCEPROP 1 LAST PATH I136
J 0
(-4950 875);
DISPLAY 0.978723 (-4950 875);
PAINT WHITE (-4950 875);
DISPLAY INVISIBLE (-4950 875);
FORCEPROP 2 LAST CDS_LOCATION C7U3
J 0
(-4950 825);
DISPLAY 0.617021 (-4950 825);
PAINT AQUA (-4950 825);
DISPLAY INVISIBLE (-4950 825);
FORCEPROP 2 LAST CDS_LIB mstr_discrete
J 0
(-5000 725);
PAINT MONO (-5000 725);
DISPLAY INVISIBLE (-5000 725);
FORCEADD GND..1
(-1400 450);
FORCEPROP 3 LASTPIN (-1400 500) SIG_NAME GND\g
J 0
(-1390 510);
DISPLAY 0.659574 (-1390 510);
PAINT MONO (-1390 510);
DISPLAY INVISIBLE (-1390 510);
FORCEPROP 1 LAST VOLTAGE 0
J 0
(-1400 450);
PAINT SKYBLUE (-1400 450);
DISPLAY INVISIBLE (-1400 450);
FORCEPROP 1 LAST SIZE 1B
J 0
(-1325 400);
DISPLAY 0.872340 (-1325 400);
PAINT AQUA (-1325 400);
DISPLAY INVISIBLE (-1325 400);
FORCEPROP 2 LAST CDS_LIB mstr_symbols
J 0
(-1400 450);
PAINT MONO (-1400 450);
DISPLAY INVISIBLE (-1400 450);
FORCEPROP 1 LAST PATH I156
J 0
(-1325 450);
DISPLAY 0.872340 (-1325 450);
PAINT AQUA (-1325 450);
DISPLAY INVISIBLE (-1325 450);
FORCEPROP 2 LAST ROOM PVPP_KLM_VR
J 0
(-1975 525);
DISPLAY 1.042553 (-1975 525);
PAINT GREEN (-1975 525);
DISPLAY INVISIBLE (-1975 525);
FORCEPROP 2 LAST BOM_COST PVPP_KLM_VR
J 0
(-2250 525);
DISPLAY 1.042553 (-2250 525);
PAINT WHITE (-2250 525);
DISPLAY INVISIBLE (-2250 525);
FORCEPROP 1 LAST BODY_TYPE PLUMBING
J 0
(-1445 407);
DISPLAY 0.340426 (-1445 407);
PAINT GREEN (-1445 407);
DISPLAY INVISIBLE (-1445 407);
FORCEPROP 1 LAST HDL_POWER GND
J 0
(-1400 600);
DISPLAY 0.872340 (-1400 600);
PAINT GREEN (-1400 600);
DISPLAY INVISIBLE (-1400 600);
FORCEADD RES..1
(-1100 550);
FORCEPROP 1 LAST LOCATION R4G25
J 0
(-1150 600);
DISPLAY 0.617021 (-1150 600);
PAINT AQUA (-1150 600);
FORCEPROP 1 LAST PART_NUMBER G21497-005
J 0
(-1225 500);
DISPLAY 0.617021 (-1225 500);
PAINT BLUE (-1225 500);
FORCEPROP 1 LAST MATERIAL CHIP
J 0
(-1100 400);
DISPLAY 0.617021 (-1100 400);
PAINT SKYBLUE (-1100 400);
FORCEPROP 1 LASTPIN (-1000 550) $PN 2
J 0
(-1038 562);
DISPLAY 0.617021 (-1038 562);
PAINT WHITE (-1038 562);
FORCEPROP 1 LASTPIN (-1200 550) $PN 1
J 0
(-1188 562);
DISPLAY 0.617021 (-1188 562);
PAINT WHITE (-1188 562);
FORCEPROP 1 LAST VALUE 0.0
J 2
(-1125 450);
DISPLAY 0.617021 (-1125 450);
PAINT SKYBLUE (-1125 450);
FORCEPROP 1 LAST TOLERANCE 5%
J 0
(-1100 450);
DISPLAY 0.617021 (-1100 450);
PAINT SKYBLUE (-1100 450);
FORCEPROP 1 LAST PACK_TYPE 0402
J 0
(-1175 350);
DISPLAY 0.617021 (-1175 350);
PAINT SKYBLUE (-1175 350);
FORCEPROP 1 LAST WATTAGE 1/16W
J 2
(-1100 400);
DISPLAY 0.617021 (-1100 400);
PAINT SKYBLUE (-1100 400);
FORCEPROP 2 LAST $SEC 1
J 0
(-1135 755);
PAINT MONO (-1135 755);
DISPLAY INVISIBLE (-1135 755);
FORCEPROP 2 LAST CDS_SEC 1
J 0
(-1140 735);
PAINT MONO (-1140 735);
DISPLAY INVISIBLE (-1140 735);
FORCEPROP 2 LAST ROOM PVPP_KLM_VR
J 0
(-1150 625);
PAINT GREEN (-1150 625);
DISPLAY INVISIBLE (-1150 625);
FORCEPROP 1 LAST PATH I157
J 0
(-1150 700);
DISPLAY 0.978723 (-1150 700);
PAINT WHITE (-1150 700);
DISPLAY INVISIBLE (-1150 700);
FORCEPROP 2 LAST CDS_LIB mstr_discrete
J 0
(-1100 550);
PAINT MONO (-1100 550);
DISPLAY INVISIBLE (-1100 550);
FORCEADD AGND_SCSI..1
(-850 450);
FORCEPROP 3 LASTPIN (-850 500) SIG_NAME AGND_PVPP_GHJ\g
J 0
(-840 510);
DISPLAY 0.659574 (-840 510);
PAINT MONO (-840 510);
DISPLAY INVISIBLE (-840 510);
FORCEPROP 1 LAST HDL_POWER AGND_PVPP_GHJ
J 1
(-775 375);
DISPLAY 0.617021 (-775 375);
PAINT GREEN (-775 375);
FORCEPROP 2 LAST BOM_COST PVPP_KLM_VR
J 0
(-1000 400);
DISPLAY 1.042553 (-1000 400);
PAINT WHITE (-1000 400);
DISPLAY INVISIBLE (-1000 400);
FORCEPROP 1 LAST PATH I158
J 0
(-775 450);
DISPLAY 0.872340 (-775 450);
PAINT AQUA (-775 450);
DISPLAY INVISIBLE (-775 450);
FORCEPROP 2 LAST ROOM PVPP_KLM_VR
J 0
(-1000 400);
DISPLAY 1.042553 (-1000 400);
PAINT GREEN (-1000 400);
DISPLAY INVISIBLE (-1000 400);
FORCEPROP 1 LAST VOLTAGE 0.0V
J 0
(-895 407);
DISPLAY 0.340426 (-895 407);
PAINT SKYBLUE (-895 407);
DISPLAY INVISIBLE (-895 407);
FORCEPROP 2 LAST CDS_LIB mstr_symbols
J 0
(-850 450);
PAINT ORANGE (-850 450);
DISPLAY INVISIBLE (-850 450);
FORCEPROP 1 LAST BODY_TYPE PLUMBING
J 0
(-895 407);
DISPLAY 0.340426 (-895 407);
PAINT GREEN (-895 407);
DISPLAY INVISIBLE (-895 407);
FORCEADD PVPP_GHJ..1
(-725 3825);
FORCEPROP 3 LASTPIN (-725 3775) SIG_NAME PVPP_GHJ\g
J 0
(-715 3785);
DISPLAY 0.659574 (-715 3785);
PAINT MONO (-715 3785);
DISPLAY INVISIBLE (-715 3785);
FORCEPROP 2 LAST ROOM PVPP_KLM_VR
J 0
(-475 3925);
PAINT ORANGE (-475 3925);
DISPLAY INVISIBLE (-475 3925);
FORCEPROP 1 LAST PATH I174
J 0
(-675 3850);
DISPLAY 0.872340 (-675 3850);
PAINT AQUA (-675 3850);
DISPLAY INVISIBLE (-675 3850);
FORCEPROP 2 LAST BOM_COST PVPP_KLM_VR
J 0
(-650 3925);
PAINT MONO (-650 3925);
DISPLAY INVISIBLE (-650 3925);
FORCEPROP 2 LAST CDS_LIB mstr_symbols
J 0
(-725 3825);
PAINT ORANGE (-725 3825);
DISPLAY INVISIBLE (-725 3825);
FORCEPROP 1 LAST VOLTAGE 2.5V
J 0
(-770 3782);
DISPLAY 0.340426 (-770 3782);
PAINT SKYBLUE (-770 3782);
DISPLAY INVISIBLE (-770 3782);
FORCEPROP 1 LAST BODY_TYPE PLUMBING
J 0
(-770 3782);
DISPLAY 0.340426 (-770 3782);
PAINT GREEN (-770 3782);
DISPLAY INVISIBLE (-770 3782);
FORCEPROP 1 LAST HDL_POWER PVPP_GHJ
J 1
(-725 3875);
DISPLAY 0.872340 (-725 3875);
PAINT GREEN (-725 3875);
DISPLAY INVISIBLE (-725 3875);
FORCEADD GND..1
(-7100 1900);
FORCEPROP 3 LASTPIN (-7100 1950) SIG_NAME GND\g
J 0
(-7090 1960);
DISPLAY 0.659574 (-7090 1960);
PAINT MONO (-7090 1960);
DISPLAY INVISIBLE (-7090 1960);
FORCEPROP 1 LAST SIZE 1B
J 0
(-7025 1850);
DISPLAY 0.680851 (-7025 1850);
PAINT ORANGE (-7025 1850);
DISPLAY INVISIBLE (-7025 1850);
FORCEPROP 1 LAST PATH I180
J 0
(-7025 1900);
DISPLAY 0.872340 (-7025 1900);
PAINT AQUA (-7025 1900);
DISPLAY INVISIBLE (-7025 1900);
FORCEPROP 2 LAST CDS_LIB mstr_symbols
J 0
(-7100 1900);
PAINT MONO (-7100 1900);
DISPLAY INVISIBLE (-7100 1900);
FORCEPROP 1 LAST VOLTAGE 0
J 0
(-7100 1900);
PAINT SKYBLUE (-7100 1900);
DISPLAY INVISIBLE (-7100 1900);
FORCEPROP 2 LAST ROOM PVPP_KLM_VR
J 0
(-7850 1975);
DISPLAY 1.042553 (-7850 1975);
PAINT GREEN (-7850 1975);
DISPLAY INVISIBLE (-7850 1975);
FORCEPROP 2 LAST BOM_COST PVPP_KLM_VR
J 0
(-7850 2025);
DISPLAY 1.042553 (-7850 2025);
PAINT WHITE (-7850 2025);
DISPLAY INVISIBLE (-7850 2025);
FORCEPROP 2 LAST BOM SYSB_CPLD
J 0
(-7850 2075);
DISPLAY 1.042553 (-7850 2075);
PAINT ORANGE (-7850 2075);
DISPLAY INVISIBLE (-7850 2075);
FORCEPROP 1 LAST BODY_TYPE PLUMBING
J 0
(-7145 1857);
DISPLAY 0.340426 (-7145 1857);
PAINT GREEN (-7145 1857);
DISPLAY INVISIBLE (-7145 1857);
FORCEPROP 1 LAST HDL_POWER GND
J 0
(-7100 2050);
DISPLAY 0.680851 (-7100 2050);
PAINT GREEN (-7100 2050);
DISPLAY INVISIBLE (-7100 2050);
FORCEADD OFFPAGE..1
(-7575 2675);
FORCEPROP 2 LAST $XR1 234 
J 0
(-7947 2675);
DISPLAY 0.638298 (-7947 2675);
PAINT MONO (-7947 2675);
FORCEPROP 2 LAST $XR0 191 
J 0
(-7827 2675);
DISPLAY 0.638298 (-7827 2675);
PAINT MONO (-7827 2675);
FORCEPROP 0 LAST TOLERANCE 1%
J 0
(-7525 2750);
PAINT SKYBLUE (-7525 2750);
DISPLAY INVISIBLE (-7525 2750);
FORCEPROP 2 LAST CDS_LIB mstr_standard
J 0
(-7575 2675);
PAINT MONO (-7575 2675);
DISPLAY INVISIBLE (-7575 2675);
FORCEPROP 2 LAST ROOM PVPP_KLM_VR
J 0
(-8125 2750);
DISPLAY 1.042553 (-8125 2750);
PAINT GREEN (-8125 2750);
DISPLAY INVISIBLE (-8125 2750);
FORCEPROP 2 LAST PATH I181
J 0
(-7825 2725);
DISPLAY 1.021277 (-7825 2725);
PAINT ORANGE (-7825 2725);
DISPLAY INVISIBLE (-7825 2725);
FORCEPROP 2 LAST BOM_COST PVPP_KLM_VR
J 0
(-8400 2750);
DISPLAY 1.042553 (-8400 2750);
PAINT WHITE (-8400 2750);
DISPLAY INVISIBLE (-8400 2750);
FORCEPROP 1 LAST OFFPAGE TRUE
J 0
(-7250 2550);
PAINT GREEN (-7250 2550);
DISPLAY INVISIBLE (-7250 2550);
FORCEPROP 1 LAST COMMENT_BODY TRUE
J 0
(-7450 2575);
DISPLAY 0.872340 (-7450 2575);
PAINT PEACH (-7450 2575);
DISPLAY INVISIBLE (-7450 2575);
FORCEADD RES..2
(-7100 2200);
FORCEPROP 1 LAST VALUE 10.0K
J 0
(-7055 2275);
DISPLAY 0.617021 (-7055 2275);
PAINT SKYBLUE (-7055 2275);
FORCEPROP 1 LAST TOLERANCE 1%
J 0
(-7055 2225);
DISPLAY 0.617021 (-7055 2225);
PAINT SKYBLUE (-7055 2225);
FORCEPROP 1 LAST WATTAGE 1/16W
J 0
(-7060 2175);
DISPLAY 0.617021 (-7060 2175);
PAINT SKYBLUE (-7060 2175);
FORCEPROP 1 LASTPIN (-7100 2300) $PN 1
J 0
(-7095 2262);
DISPLAY 0.617021 (-7095 2262);
PAINT WHITE (-7095 2262);
FORCEPROP 1 LASTPIN (-7100 2100) $PN 2
J 0
(-7095 2110);
DISPLAY 0.617021 (-7095 2110);
PAINT WHITE (-7095 2110);
FORCEPROP 1 LAST LOCATION R4G5
J 0
(-7055 2325);
DISPLAY 0.617021 (-7055 2325);
PAINT AQUA (-7055 2325);
FORCEPROP 1 LAST MATERIAL CHIP
J 0
(-7060 2125);
DISPLAY 0.617021 (-7060 2125);
PAINT SKYBLUE (-7060 2125);
FORCEPROP 1 LAST PART_NUMBER G21796-016
J 0
(-7085 2075);
DISPLAY 0.617021 (-7085 2075);
PAINT BLUE (-7085 2075);
FORCEPROP 1 LAST PACK_TYPE 0402
J 0
(-7060 2025);
DISPLAY 0.617021 (-7060 2025);
PAINT SKYBLUE (-7060 2025);
FORCEPROP 2 LAST BOM_COST PVPP_KLM_VR
J 0
(-7050 2425);
DISPLAY 1.042553 (-7050 2425);
PAINT WHITE (-7050 2425);
DISPLAY INVISIBLE (-7050 2425);
FORCEPROP 0 LAST BOM SYSB_CPLD
J 0
(-7050 2525);
DISPLAY 1.042553 (-7050 2525);
PAINT ORANGE (-7050 2525);
DISPLAY INVISIBLE (-7050 2525);
FORCEPROP 2 LAST CDS_SEC 1
J 0
(-7050 2425);
DISPLAY 1.042553 (-7050 2425);
PAINT ORANGE (-7050 2425);
DISPLAY INVISIBLE (-7050 2425);
FORCEPROP 2 LAST $SEC 1
J 0
(-7050 2425);
DISPLAY 0.680851 (-7050 2425);
PAINT MONO (-7050 2425);
DISPLAY INVISIBLE (-7050 2425);
FORCEPROP 2 LAST CDS_LOCATION R4G5
J 0
(-7055 2325);
DISPLAY 0.617021 (-7055 2325);
PAINT AQUA (-7055 2325);
DISPLAY INVISIBLE (-7055 2325);
FORCEPROP 1 LAST PATH I182
J 0
(-7050 2375);
DISPLAY 0.978723 (-7050 2375);
PAINT WHITE (-7050 2375);
DISPLAY INVISIBLE (-7050 2375);
FORCEPROP 2 LAST ROOM PVPP_KLM_VR
J 0
(-7050 2425);
DISPLAY 1.042553 (-7050 2425);
PAINT GREEN (-7050 2425);
DISPLAY INVISIBLE (-7050 2425);
FORCEPROP 2 LAST CDS_LIB mstr_discrete
J 0
(-7100 2200);
PAINT MONO (-7100 2200);
DISPLAY INVISIBLE (-7100 2200);
FORCEADD CAP..1
R 2
(-6500 2200);
FORCEPROP 1 LASTPIN (-6500 2300) $PN 1
J 2
(-6510 2280);
DISPLAY 0.617021 (-6510 2280);
PAINT WHITE (-6510 2280);
FORCEPROP 1 LASTPIN (-6500 2100) $PN 2
J 2
(-6510 2080);
DISPLAY 0.617021 (-6510 2080);
PAINT WHITE (-6510 2080);
FORCEPROP 1 LAST VOLTAGE 50V
J 2
(-6550 2200);
DISPLAY 0.617021 (-6550 2200);
PAINT SKYBLUE (-6550 2200);
FORCEPROP 1 LAST LOCATION C4G7
J 2
(-6550 2300);
DISPLAY 0.617021 (-6550 2300);
PAINT AQUA (-6550 2300);
FORCEPROP 1 LAST VALUE 1000PF
J 2
(-6550 2250);
DISPLAY 0.617021 (-6550 2250);
PAINT SKYBLUE (-6550 2250);
FORCEPROP 1 LAST TOLERANCE 10%
J 2
(-6550 2150);
DISPLAY 0.617021 (-6550 2150);
PAINT SKYBLUE (-6550 2150);
FORCEPROP 1 LAST MATERIAL EMPTY
J 2
(-6550 2100);
DISPLAY 0.617021 (-6550 2100);
PAINT RED (-6550 2100);
FORCEPROP 1 LAST PART_NUMBER A36096-046
J 2
(-6525 2050);
DISPLAY 0.617021 (-6525 2050);
PAINT BLUE (-6525 2050);
FORCEPROP 1 LAST PACK_TYPE 0402LF
J 2
(-6550 2000);
DISPLAY 0.617021 (-6550 2000);
PAINT SKYBLUE (-6550 2000);
FORCEPROP 0 LAST FIN VR_1P2
J 2
(-6550 2500);
PAINT ORANGE (-6550 2500);
DISPLAY INVISIBLE (-6550 2500);
FORCEPROP 0 LAST REUSE_ID 1
J 2
(-6550 2400);
DISPLAY 1.042553 (-6550 2400);
PAINT ORANGE (-6550 2400);
DISPLAY INVISIBLE (-6550 2400);
FORCEPROP 2 LAST CDS_SEC 1
J 2
(-6550 2400);
DISPLAY 1.042553 (-6550 2400);
PAINT ORANGE (-6550 2400);
DISPLAY INVISIBLE (-6550 2400);
FORCEPROP 2 LAST $SEC 1
J 2
(-6550 2400);
DISPLAY 0.680851 (-6550 2400);
PAINT MONO (-6550 2400);
DISPLAY INVISIBLE (-6550 2400);
FORCEPROP 1 LAST PATH I183
J 2
(-6550 2350);
DISPLAY 0.978723 (-6550 2350);
PAINT WHITE (-6550 2350);
DISPLAY INVISIBLE (-6550 2350);
FORCEPROP 2 LAST CDS_LOCATION C4G7
J 2
(-6550 2300);
DISPLAY 0.617021 (-6550 2300);
PAINT AQUA (-6550 2300);
DISPLAY INVISIBLE (-6550 2300);
FORCEPROP 2 LAST CDS_LIB mstr_discrete
J 2
(-6500 2200);
PAINT MONO (-6500 2200);
DISPLAY INVISIBLE (-6500 2200);
FORCEPROP 2 LAST BOM_COST PVPP_KLM_VR
J 2
(-6500 2200);
PAINT WHITE (-6500 2200);
DISPLAY INVISIBLE (-6500 2200);
FORCEPROP 2 LAST ROOM PVPP_KLM_VR
J 2
(-6500 2200);
PAINT GREEN (-6500 2200);
DISPLAY INVISIBLE (-6500 2200);
FORCEADD RES..2
(-4150 1100);
FORCEPROP 1 LAST LOCATION R4G14
J 0
(-4105 1225);
DISPLAY 0.617021 (-4105 1225);
PAINT AQUA (-4105 1225);
FORCEPROP 1 LAST MATERIAL CHIP
J 0
(-4110 1025);
DISPLAY 0.617021 (-4110 1025);
PAINT SKYBLUE (-4110 1025);
FORCEPROP 1 LASTPIN (-4150 1000) $PN 2
J 0
(-4145 1010);
DISPLAY 0.617021 (-4145 1010);
PAINT WHITE (-4145 1010);
FORCEPROP 1 LAST WATTAGE 1/16W
J 0
(-4110 1075);
DISPLAY 0.617021 (-4110 1075);
PAINT SKYBLUE (-4110 1075);
FORCEPROP 1 LASTPIN (-4150 1200) $PN 1
J 0
(-4145 1162);
DISPLAY 0.617021 (-4145 1162);
PAINT WHITE (-4145 1162);
FORCEPROP 1 LAST TOLERANCE 1%
J 0
(-4105 1125);
DISPLAY 0.617021 (-4105 1125);
PAINT SKYBLUE (-4105 1125);
FORCEPROP 1 LAST VALUE 1.00K
J 0
(-4105 1175);
DISPLAY 0.617021 (-4105 1175);
PAINT SKYBLUE (-4105 1175);
FORCEPROP 1 LAST PART_NUMBER G21796-026
J 0
(-4110 975);
DISPLAY 0.617021 (-4110 975);
PAINT BLUE (-4110 975);
FORCEPROP 1 LAST PACK_TYPE 0402
J 0
(-4110 925);
DISPLAY 0.617021 (-4110 925);
PAINT SKYBLUE (-4110 925);
FORCEPROP 2 LAST BOM_COST PVPP_KLM_VR
J 0
(-4090 1290);
DISPLAY 1.042553 (-4090 1290);
PAINT WHITE (-4090 1290);
DISPLAY INVISIBLE (-4090 1290);
FORCEPROP 2 LAST ROOM PVPP_KLM_VR
J 0
(-4090 1265);
PAINT GREEN (-4090 1265);
DISPLAY INVISIBLE (-4090 1265);
FORCEPROP 2 LAST REUSE_ID 21
J 0
(-4100 1325);
DISPLAY 1.042553 (-4100 1325);
PAINT ORANGE (-4100 1325);
DISPLAY INVISIBLE (-4100 1325);
FORCEPROP 2 LAST SEC_TYPE 0402
J 0
(-4100 1325);
DISPLAY 1.042553 (-4100 1325);
PAINT ORANGE (-4100 1325);
DISPLAY INVISIBLE (-4100 1325);
FORCEPROP 2 LAST SEC 1
J 0
(-4100 1325);
DISPLAY 0.680851 (-4100 1325);
PAINT MONO (-4100 1325);
DISPLAY INVISIBLE (-4100 1325);
FORCEPROP 1 LAST PATH I185
J 0
(-4100 1275);
DISPLAY 0.978723 (-4100 1275);
PAINT WHITE (-4100 1275);
DISPLAY INVISIBLE (-4100 1275);
FORCEPROP 2 LAST CDS_LIB mstr_discrete
J 0
(-4150 1100);
PAINT MONO (-4150 1100);
DISPLAY INVISIBLE (-4150 1100);
FORCEPROP 2 LAST CDS_LOCATION R4G14
J 0
(-4105 1225);
DISPLAY 0.617021 (-4105 1225);
PAINT AQUA (-4105 1225);
DISPLAY INVISIBLE (-4105 1225);
FORCEADD P3V3_STBY..1
(-4150 1375);
FORCEPROP 3 LASTPIN (-4150 1325) SIG_NAME P3V3_STBY\g
J 0
(-4140 1335);
DISPLAY 0.659574 (-4140 1335);
PAINT MONO (-4140 1335);
DISPLAY INVISIBLE (-4140 1335);
FORCEPROP 1 LAST VOLTAGE +3.3V
J 0
(-3950 1525);
DISPLAY 1.021277 (-3950 1525);
PAINT SKYBLUE (-3950 1525);
DISPLAY INVISIBLE (-3950 1525);
FORCEPROP 2 LAST CDS_LIB mstr_symbols
J 0
(-4150 1375);
PAINT MONO (-4150 1375);
DISPLAY INVISIBLE (-4150 1375);
FORCEPROP 1 LAST SIZE 1B
J 0
(-4105 1397);
DISPLAY 0.340426 (-4105 1397);
PAINT GREEN (-4105 1397);
DISPLAY INVISIBLE (-4105 1397);
FORCEPROP 1 LAST PATH I186
J 0
(-4105 1377);
DISPLAY 0.340426 (-4105 1377);
PAINT GREEN (-4105 1377);
DISPLAY INVISIBLE (-4105 1377);
FORCEPROP 1 LAST BODY_TYPE PLUMBING
J 0
(-4195 1332);
DISPLAY 0.340426 (-4195 1332);
PAINT GREEN (-4195 1332);
DISPLAY INVISIBLE (-4195 1332);
FORCEPROP 1 LAST HDL_POWER P3V3_STBY
J 0
(-4450 1250);
DISPLAY 0.872340 (-4450 1250);
PAINT ORANGE (-4450 1250);
DISPLAY INVISIBLE (-4450 1250);
FORCEADD CAP..1
(-5800 2350);
FORCEPROP 1 LAST LOCATION C6U6
J 0
(-5750 2450);
DISPLAY 0.617021 (-5750 2450);
PAINT AQUA (-5750 2450);
FORCEPROP 1 LASTPIN (-5800 2450) $PN 1
J 0
(-5790 2430);
DISPLAY 0.617021 (-5790 2430);
PAINT ORANGE (-5790 2430);
FORCEPROP 1 LASTPIN (-5800 2250) $PN 2
J 0
(-5790 2230);
DISPLAY 0.617021 (-5790 2230);
PAINT ORANGE (-5790 2230);
FORCEPROP 1 LAST VOLTAGE 6.3V
J 0
(-5725 2350);
DISPLAY 0.617021 (-5725 2350);
PAINT SKYBLUE (-5725 2350);
FORCEPROP 1 LAST VALUE 4.7UF
J 0
(-5750 2400);
DISPLAY 0.617021 (-5750 2400);
PAINT SKYBLUE (-5750 2400);
FORCEPROP 1 LAST TOLERANCE 10%
J 0
(-5725 2300);
DISPLAY 0.617021 (-5725 2300);
PAINT SKYBLUE (-5725 2300);
FORCEPROP 1 LAST PACK_TYPE 0603
J 0
(-5750 2250);
DISPLAY 0.617021 (-5750 2250);
PAINT SKYBLUE (-5750 2250);
FORCEPROP 1 LAST PART_NUMBER E15431-003
J 0
(-5775 2200);
DISPLAY 0.617021 (-5775 2200);
PAINT BLUE (-5775 2200);
FORCEPROP 1 LAST MATERIAL X6S
J 0
(-5750 2150);
DISPLAY 0.617021 (-5750 2150);
PAINT SKYBLUE (-5750 2150);
FORCEPROP 0 LAST CONFIG 078.47521.08BD
J 0
(-5900 2125);
DISPLAY 0.638298 (-5900 2125);
PAINT BROWN (-5900 2125);
DISPLAY BOTH (-5900 2125);
FORCEPROP 2 LAST SEC 1
J 0
(-5750 2550);
PAINT MONO (-5750 2550);
DISPLAY INVISIBLE (-5750 2550);
FORCEPROP 2 LAST CDS_LOCATION C6U6
J 0
(-5750 2450);
DISPLAY 0.617021 (-5750 2450);
PAINT AQUA (-5750 2450);
DISPLAY INVISIBLE (-5750 2450);
FORCEPROP 1 LAST PATH I187
J 0
(-5750 2500);
DISPLAY 0.978723 (-5750 2500);
PAINT WHITE (-5750 2500);
DISPLAY INVISIBLE (-5750 2500);
FORCEPROP 2 LAST ROOM PVPP_KLM_VR
J 0
(-5750 2475);
PAINT GREEN (-5750 2475);
DISPLAY INVISIBLE (-5750 2475);
FORCEPROP 2 LAST BOM_COST PVPP_KLM_VR
J 0
(-5750 2500);
DISPLAY 1.042553 (-5750 2500);
PAINT WHITE (-5750 2500);
DISPLAY INVISIBLE (-5750 2500);
FORCEPROP 2 LAST SEC_TYPE 0603
J 0
(-5750 2550);
DISPLAY 1.021277 (-5750 2550);
PAINT ORANGE (-5750 2550);
DISPLAY INVISIBLE (-5750 2550);
FORCEPROP 2 LAST REUSE_ID 26
J 0
(-5750 2550);
DISPLAY 1.042553 (-5750 2550);
PAINT ORANGE (-5750 2550);
DISPLAY INVISIBLE (-5750 2550);
FORCEPROP 2 LAST CDS_LIB mstr_discrete
J 0
(-5800 2350);
PAINT MONO (-5800 2350);
DISPLAY INVISIBLE (-5800 2350);
FORCEADD CAP..1
(-5000 2025);
FORCEPROP 1 LASTPIN (-5000 2125) $PN 1
J 0
(-4990 2105);
DISPLAY 0.617021 (-4990 2105);
PAINT ORANGE (-4990 2105);
FORCEPROP 1 LAST VALUE 0.027UF
J 0
(-4950 2075);
DISPLAY 0.617021 (-4950 2075);
PAINT SKYBLUE (-4950 2075);
FORCEPROP 1 LAST LOCATION C4G8
J 0
(-4950 2125);
DISPLAY 0.617021 (-4950 2125);
PAINT AQUA (-4950 2125);
FORCEPROP 1 LASTPIN (-5000 1925) $PN 2
J 0
(-4990 1905);
DISPLAY 0.617021 (-4990 1905);
PAINT ORANGE (-4990 1905);
FORCEPROP 1 LAST VOLTAGE 16V
J 0
(-4925 2025);
DISPLAY 0.617021 (-4925 2025);
PAINT SKYBLUE (-4925 2025);
FORCEPROP 1 LAST TOLERANCE 10%
J 0
(-4925 1975);
DISPLAY 0.617021 (-4925 1975);
PAINT SKYBLUE (-4925 1975);
FORCEPROP 1 LAST PACK_TYPE 0402
J 0
(-4950 1925);
DISPLAY 0.617021 (-4950 1925);
PAINT SKYBLUE (-4950 1925);
FORCEPROP 1 LAST MATERIAL X7R
J 0
(-4950 1825);
DISPLAY 0.617021 (-4950 1825);
PAINT SKYBLUE (-4950 1825);
FORCEPROP 1 LAST PART_NUMBER A36096-129
J 0
(-4975 1875);
DISPLAY 0.617021 (-4975 1875);
PAINT BLUE (-4975 1875);
FORCEPROP 2 LAST ROOM PVPP_KLM_VR
J 0
(-4950 2150);
PAINT GREEN (-4950 2150);
DISPLAY INVISIBLE (-4950 2150);
FORCEPROP 1 LAST PATH I194
J 0
(-4950 2175);
DISPLAY 0.978723 (-4950 2175);
PAINT WHITE (-4950 2175);
DISPLAY INVISIBLE (-4950 2175);
FORCEPROP 2 LAST CDS_LOCATION C4G8
J 0
(-4950 2125);
DISPLAY 0.617021 (-4950 2125);
PAINT AQUA (-4950 2125);
DISPLAY INVISIBLE (-4950 2125);
FORCEPROP 0 LAST SEC 1
J 0
(-4950 2175);
DISPLAY 0.680851 (-4950 2175);
PAINT MONO (-4950 2175);
DISPLAY INVISIBLE (-4950 2175);
FORCEPROP 2 LAST BOM_COST PVPP_KLM_VR
J 0
(-4950 2175);
DISPLAY 1.042553 (-4950 2175);
PAINT WHITE (-4950 2175);
DISPLAY INVISIBLE (-4950 2175);
FORCEPROP 2 LAST REUSE_ID 26
J 0
(-4950 2225);
DISPLAY 1.042553 (-4950 2225);
PAINT ORANGE (-4950 2225);
DISPLAY INVISIBLE (-4950 2225);
FORCEPROP 2 LAST SEC_TYPE 0402
J 0
(-4950 2225);
DISPLAY 1.021277 (-4950 2225);
PAINT ORANGE (-4950 2225);
DISPLAY INVISIBLE (-4950 2225);
FORCEPROP 2 LAST CDS_LIB mstr_discrete
J 0
(-5000 2025);
PAINT MONO (-5000 2025);
DISPLAY INVISIBLE (-5000 2025);
FORCEADD GND..1
(-5000 3775);
FORCEPROP 3 LASTPIN (-5000 3825) SIG_NAME GND\g
J 0
(-4990 3835);
DISPLAY 0.659574 (-4990 3835);
PAINT MONO (-4990 3835);
DISPLAY INVISIBLE (-4990 3835);
FORCEPROP 1 LAST SIZE 1B
J 0
(-4925 3725);
DISPLAY 0.872340 (-4925 3725);
PAINT GREEN (-4925 3725);
DISPLAY INVISIBLE (-4925 3725);
FORCEPROP 1 LAST PATH I195
J 0
(-4925 3775);
DISPLAY 0.872340 (-4925 3775);
PAINT AQUA (-4925 3775);
DISPLAY INVISIBLE (-4925 3775);
FORCEPROP 2 LAST CDS_LIB mstr_symbols
J 0
(-5000 3775);
PAINT MONO (-5000 3775);
DISPLAY INVISIBLE (-5000 3775);
FORCEPROP 1 LAST VOLTAGE 0
J 0
(-5000 3775);
PAINT SKYBLUE (-5000 3775);
DISPLAY INVISIBLE (-5000 3775);
FORCEPROP 2 LAST ROOM PVPP_KLM_VR
J 0
(-5575 3850);
DISPLAY 1.042553 (-5575 3850);
PAINT GREEN (-5575 3850);
DISPLAY INVISIBLE (-5575 3850);
FORCEPROP 2 LAST BOM_COST PVPP_KLM_VR
J 0
(-5850 3850);
DISPLAY 1.042553 (-5850 3850);
PAINT WHITE (-5850 3850);
DISPLAY INVISIBLE (-5850 3850);
FORCEPROP 1 LAST BODY_TYPE PLUMBING
J 0
(-5045 3732);
DISPLAY 0.340426 (-5045 3732);
PAINT GREEN (-5045 3732);
DISPLAY INVISIBLE (-5045 3732);
FORCEPROP 1 LAST HDL_POWER GND
J 0
(-5000 3925);
DISPLAY 0.872340 (-5000 3925);
PAINT GREEN (-5000 3925);
DISPLAY INVISIBLE (-5000 3925);
FORCEADD CAP..1
(-5000 4000);
FORCEPROP 1 LAST LOCATION C4G4
J 0
(-4950 4100);
DISPLAY 0.617021 (-4950 4100);
PAINT AQUA (-4950 4100);
FORCEPROP 1 LASTPIN (-5000 4100) $PN 1
J 0
(-4990 4080);
DISPLAY 0.617021 (-4990 4080);
PAINT WHITE (-4990 4080);
FORCEPROP 1 LAST VOLTAGE 16V
J 0
(-4950 4000);
DISPLAY 0.617021 (-4950 4000);
PAINT SKYBLUE (-4950 4000);
FORCEPROP 1 LAST TOLERANCE 10%
J 0
(-4950 3950);
DISPLAY 0.617021 (-4950 3950);
PAINT SKYBLUE (-4950 3950);
FORCEPROP 1 LAST MATERIAL X6S
J 0
(-4950 3900);
DISPLAY 0.617021 (-4950 3900);
PAINT SKYBLUE (-4950 3900);
FORCEPROP 1 LAST PACK_TYPE 0402
J 0
(-4950 3800);
DISPLAY 0.617021 (-4950 3800);
PAINT SKYBLUE (-4950 3800);
FORCEPROP 1 LAST VALUE 1.0UF
J 0
(-4950 4050);
DISPLAY 0.617021 (-4950 4050);
PAINT SKYBLUE (-4950 4050);
FORCEPROP 1 LAST PART_NUMBER D97712-011
J 0
(-4950 3850);
DISPLAY 0.617021 (-4950 3850);
PAINT BLUE (-4950 3850);
FORCEPROP 1 LASTPIN (-5000 3900) $PN 2
J 0
(-4990 3880);
DISPLAY 0.617021 (-4990 3880);
PAINT WHITE (-4990 3880);
FORCEPROP 0 LAST FIN VR_1P2
J 0
(-4950 4300);
PAINT ORANGE (-4950 4300);
DISPLAY INVISIBLE (-4950 4300);
FORCEPROP 0 LAST REUSE_ID 1
J 0
(-4950 4200);
DISPLAY 1.042553 (-4950 4200);
PAINT ORANGE (-4950 4200);
DISPLAY INVISIBLE (-4950 4200);
FORCEPROP 2 LAST CDS_SEC 1
J 0
(-4950 4200);
DISPLAY 1.042553 (-4950 4200);
PAINT ORANGE (-4950 4200);
DISPLAY INVISIBLE (-4950 4200);
FORCEPROP 2 LAST $SEC 1
J 0
(-4950 4200);
DISPLAY 0.680851 (-4950 4200);
PAINT MONO (-4950 4200);
DISPLAY INVISIBLE (-4950 4200);
FORCEPROP 2 LAST CDS_LOCATION C4G4
J 0
(-4950 4100);
DISPLAY 0.617021 (-4950 4100);
PAINT AQUA (-4950 4100);
DISPLAY INVISIBLE (-4950 4100);
FORCEPROP 1 LAST PATH I196
J 0
(-4950 4150);
DISPLAY 0.978723 (-4950 4150);
PAINT WHITE (-4950 4150);
DISPLAY INVISIBLE (-4950 4150);
FORCEPROP 2 LAST BOM_COST PVPP_KLM_VR
J 0
(-5000 4000);
PAINT WHITE (-5000 4000);
DISPLAY INVISIBLE (-5000 4000);
FORCEPROP 2 LAST CDS_LIB mstr_discrete
J 0
(-5000 4000);
PAINT MONO (-5000 4000);
DISPLAY INVISIBLE (-5000 4000);
FORCEPROP 2 LAST ROOM PVPP_KLM_VR
J 0
(-5000 4000);
PAINT GREEN (-5000 4000);
DISPLAY INVISIBLE (-5000 4000);
FORCEADD P12V_STBY..1
(-7775 4350);
FORCEPROP 3 LASTPIN (-7775 4300) SIG_NAME P12V_STBY\g
J 0
(-7765 4310);
DISPLAY 0.659574 (-7765 4310);
PAINT MONO (-7765 4310);
DISPLAY INVISIBLE (-7765 4310);
FORCEPROP 1 LAST VOLTAGE 12.0V
J 0
(-7820 4307);
DISPLAY 0.340426 (-7820 4307);
PAINT SKYBLUE (-7820 4307);
DISPLAY INVISIBLE (-7820 4307);
FORCEPROP 1 LAST PATH I197
J 0
(-7730 4352);
DISPLAY 0.340426 (-7730 4352);
PAINT GREEN (-7730 4352);
DISPLAY INVISIBLE (-7730 4352);
FORCEPROP 2 LAST CDS_LIB mstr_symbols
J 0
(-7775 4350);
PAINT ORANGE (-7775 4350);
DISPLAY INVISIBLE (-7775 4350);
FORCEPROP 1 LAST SIZE 1B
J 0
(-7730 4372);
DISPLAY 0.340426 (-7730 4372);
PAINT GREEN (-7730 4372);
DISPLAY INVISIBLE (-7730 4372);
FORCEPROP 1 LAST BODY_TYPE PLUMBING
J 0
(-7820 4307);
DISPLAY 0.340426 (-7820 4307);
PAINT GREEN (-7820 4307);
DISPLAY INVISIBLE (-7820 4307);
FORCEPROP 1 LAST HDL_POWER P12V_STBY
J 0
(-8075 4225);
DISPLAY 0.872340 (-8075 4225);
PAINT ORANGE (-8075 4225);
DISPLAY INVISIBLE (-8075 4225);
FORCEADD FERRITE..1
(-7600 4150);
FORCEPROP 1 LAST MATERIAL FB
J 0
(-7595 4050);
DISPLAY 0.617021 (-7595 4050);
PAINT SKYBLUE (-7595 4050);
FORCEPROP 1 LAST PACK_TYPE SM
J 0
(-7520 4050);
DISPLAY 0.617021 (-7520 4050);
PAINT SKYBLUE (-7520 4050);
FORCEPROP 1 LAST LOCATION FB4G1
J 0
(-7695 4205);
DISPLAY 0.617021 (-7695 4205);
PAINT AQUA (-7695 4205);
FORCEPROP 1 LASTPIN (-7700 4150) $PN 1
J 2
(-7665 4160);
DISPLAY 0.617021 (-7665 4160);
PAINT WHITE (-7665 4160);
FORCEPROP 1 LASTPIN (-7500 4150) $PN 2
J 0
(-7520 4160);
DISPLAY 0.617021 (-7520 4160);
PAINT WHITE (-7520 4160);
FORCEPROP 1 LAST VALUE 22
J 2
(-7620 4050);
DISPLAY 0.617021 (-7620 4050);
PAINT SKYBLUE (-7620 4050);
FORCEPROP 1 LAST PART_NUMBER 656554-051
J 0
(-7695 4265);
DISPLAY 0.617021 (-7695 4265);
PAINT BLUE (-7695 4265);
FORCEPROP 2 LAST CDS_LOCATION FB4G1
J 0
(-7695 4205);
DISPLAY 0.617021 (-7695 4205);
PAINT AQUA (-7695 4205);
DISPLAY INVISIBLE (-7695 4205);
FORCEPROP 0 LAST TOLERANCE 1%
J 0
(-7675 4300);
PAINT SKYBLUE (-7675 4300);
DISPLAY INVISIBLE (-7675 4300);
FORCEPROP 1 LAST PATH I198
J 0
(-7695 4315);
DISPLAY 0.872340 (-7695 4315);
PAINT PURPLE (-7695 4315);
DISPLAY INVISIBLE (-7695 4315);
FORCEPROP 2 LAST CDS_LIB mstr_discrete
J 0
(-7600 4150);
PAINT MONO (-7600 4150);
DISPLAY INVISIBLE (-7600 4150);
FORCEPROP 2 LAST ROOM PVPP_KLM_VR
J 0
(-7675 4300);
DISPLAY 1.659574 (-7675 4300);
PAINT GREEN (-7675 4300);
DISPLAY INVISIBLE (-7675 4300);
FORCEPROP 2 LAST SEC_TYPE SM
J 0
(-7675 4375);
DISPLAY 1.659574 (-7675 4375);
PAINT ORANGE (-7675 4375);
DISPLAY INVISIBLE (-7675 4375);
FORCEPROP 2 LAST SEC 1
J 0
(-7675 4375);
DISPLAY 1.106383 (-7675 4375);
PAINT MONO (-7675 4375);
DISPLAY INVISIBLE (-7675 4375);
FORCEADD GND..1
(-3800 325);
FORCEPROP 3 LASTPIN (-3800 375) SIG_NAME GND\g
J 0
(-3790 385);
DISPLAY 0.659574 (-3790 385);
PAINT MONO (-3790 385);
DISPLAY INVISIBLE (-3790 385);
FORCEPROP 1 LAST VOLTAGE 0
J 0
(-3800 400);
PAINT SKYBLUE (-3800 400);
DISPLAY INVISIBLE (-3800 400);
FORCEPROP 2 LAST CDS_LIB mstr_symbols
J 0
(-3800 400);
PAINT MONO (-3800 400);
DISPLAY INVISIBLE (-3800 400);
FORCEPROP 1 LAST SIZE 1B
J 0
(-3725 350);
DISPLAY 0.893617 (-3725 350);
PAINT GREEN (-3725 350);
DISPLAY INVISIBLE (-3725 350);
FORCEPROP 1 LAST PATH I200
J 0
(-3725 325);
DISPLAY 0.872340 (-3725 325);
PAINT AQUA (-3725 325);
DISPLAY INVISIBLE (-3725 325);
FORCEPROP 2 LAST ROOM PVPP_KLM_VR
J 0
(-4450 475);
PAINT GREEN (-4450 475);
DISPLAY INVISIBLE (-4450 475);
FORCEPROP 2 LAST BOM_COST PVPP_KLM_VR
J 0
(-4700 475);
DISPLAY 1.042553 (-4700 475);
PAINT WHITE (-4700 475);
DISPLAY INVISIBLE (-4700 475);
FORCEPROP 1 LAST BODY_TYPE PLUMBING
J 0
(-3845 282);
DISPLAY 0.340426 (-3845 282);
PAINT GREEN (-3845 282);
DISPLAY INVISIBLE (-3845 282);
FORCEPROP 1 LAST HDL_POWER GND
J 0
(-3800 550);
DISPLAY 0.893617 (-3800 550);
PAINT GREEN (-3800 550);
DISPLAY INVISIBLE (-3800 550);
FORCEADD CAP..1
(-3800 575);
FORCEPROP 1 LAST PART_NUMBER A36096-046
J 0
(-3750 375);
DISPLAY 0.617021 (-3750 375);
PAINT BLUE (-3750 375);
FORCEPROP 1 LAST PACK_TYPE 0402LF
J 0
(-3750 425);
DISPLAY 0.617021 (-3750 425);
PAINT SKYBLUE (-3750 425);
FORCEPROP 1 LASTPIN (-3800 475) $PN 2
J 0
(-3790 455);
DISPLAY 0.617021 (-3790 455);
PAINT WHITE (-3790 455);
FORCEPROP 1 LAST VALUE 1000PF
J 0
(-3750 625);
DISPLAY 0.617021 (-3750 625);
PAINT SKYBLUE (-3750 625);
FORCEPROP 1 LAST TOLERANCE 10%
J 0
(-3750 525);
DISPLAY 0.617021 (-3750 525);
PAINT SKYBLUE (-3750 525);
FORCEPROP 1 LAST LOCATION C4G9
J 0
(-3750 675);
DISPLAY 0.617021 (-3750 675);
PAINT AQUA (-3750 675);
FORCEPROP 1 LASTPIN (-3800 675) $PN 1
J 0
(-3790 655);
DISPLAY 0.617021 (-3790 655);
PAINT WHITE (-3790 655);
FORCEPROP 1 LAST MATERIAL X7R
J 0
(-3750 475);
DISPLAY 0.617021 (-3750 475);
PAINT SKYBLUE (-3750 475);
FORCEPROP 1 LAST VOLTAGE 50V
J 0
(-3750 575);
DISPLAY 0.617021 (-3750 575);
PAINT SKYBLUE (-3750 575);
FORCEPROP 2 LAST $SEC 1
J 2
(-3750 775);
DISPLAY 0.680851 (-3750 775);
PAINT MONO (-3750 775);
DISPLAY INVISIBLE (-3750 775);
FORCEPROP 2 LAST CDS_SEC 1
J 2
(-3750 775);
DISPLAY 1.042553 (-3750 775);
PAINT ORANGE (-3750 775);
DISPLAY INVISIBLE (-3750 775);
FORCEPROP 2 LAST REUSE_ID 17
J 0
(-3750 775);
DISPLAY 1.042553 (-3750 775);
PAINT ORANGE (-3750 775);
DISPLAY INVISIBLE (-3750 775);
FORCEPROP 2 LAST BOM_COST PVPP_KLM_VR
J 0
(-3800 575);
PAINT WHITE (-3800 575);
DISPLAY INVISIBLE (-3800 575);
FORCEPROP 2 LAST CDS_LIB mstr_discrete
J 2
(-3800 575);
PAINT MONO (-3800 575);
DISPLAY INVISIBLE (-3800 575);
FORCEPROP 2 LAST CDS_LOCATION C4G9
J 0
(-3750 675);
DISPLAY 0.617021 (-3750 675);
PAINT AQUA (-3750 675);
DISPLAY INVISIBLE (-3750 675);
FORCEPROP 1 LAST PATH I201
J 0
(-3750 725);
DISPLAY 0.978723 (-3750 725);
PAINT WHITE (-3750 725);
DISPLAY INVISIBLE (-3750 725);
FORCEPROP 2 LAST ROOM PVPP_KLM_VR
J 0
(-3800 575);
PAINT GREEN (-3800 575);
DISPLAY INVISIBLE (-3800 575);
FORCEADD OFFPAGE..2
(-2550 825);
FORCEPROP 2 LAST $XR0 190 
J 0
(-2361 825);
DISPLAY 0.638298 (-2361 825);
PAINT MONO (-2361 825);
FORCEPROP 2 LAST PATH I202
J 0
(-2250 875);
DISPLAY 1.021277 (-2250 875);
PAINT ORANGE (-2250 875);
DISPLAY INVISIBLE (-2250 875);
FORCEPROP 0 LAST TOLERANCE 1%
J 0
(-2375 900);
PAINT SKYBLUE (-2375 900);
DISPLAY INVISIBLE (-2375 900);
FORCEPROP 2 LAST CDS_LIB mstr_standard
J 2
(-2550 825);
PAINT MONO (-2550 825);
DISPLAY INVISIBLE (-2550 825);
FORCEPROP 2 LAST ROOM PVPP_KLM_VR
J 0
(-2975 900);
DISPLAY 1.042553 (-2975 900);
PAINT GREEN (-2975 900);
DISPLAY INVISIBLE (-2975 900);
FORCEPROP 2 LAST BOM_COST PVPP_KLM_VR
J 0
(-3250 900);
DISPLAY 1.042553 (-3250 900);
PAINT WHITE (-3250 900);
DISPLAY INVISIBLE (-3250 900);
FORCEPROP 1 LAST OFFPAGE TRUE
J 0
(-2225 700);
PAINT GREEN (-2225 700);
DISPLAY INVISIBLE (-2225 700);
FORCEPROP 1 LAST COMMENT_BODY TRUE
J 0
(-2595 730);
DISPLAY 0.872340 (-2595 730);
PAINT PEACH (-2595 730);
DISPLAY INVISIBLE (-2595 730);
FORCEADD GND..1
(-3000 1775);
FORCEPROP 3 LASTPIN (-3000 1825) SIG_NAME GND\g
J 0
(-2990 1835);
DISPLAY 0.659574 (-2990 1835);
PAINT MONO (-2990 1835);
DISPLAY INVISIBLE (-2990 1835);
FORCEPROP 1 LAST SIZE 1B
J 0
(-2925 1800);
DISPLAY 0.893617 (-2925 1800);
PAINT GREEN (-2925 1800);
DISPLAY INVISIBLE (-2925 1800);
FORCEPROP 1 LAST VOLTAGE 0
J 0
(-3000 1850);
PAINT SKYBLUE (-3000 1850);
DISPLAY INVISIBLE (-3000 1850);
FORCEPROP 2 LAST CDS_LIB mstr_symbols
J 0
(-3000 1775);
PAINT MONO (-3000 1775);
DISPLAY INVISIBLE (-3000 1775);
FORCEPROP 1 LAST PATH I203
J 0
(-2925 1775);
DISPLAY 0.872340 (-2925 1775);
PAINT AQUA (-2925 1775);
DISPLAY INVISIBLE (-2925 1775);
FORCEPROP 2 LAST ROOM PVPP_KLM_VR
J 0
(-3650 1925);
PAINT GREEN (-3650 1925);
DISPLAY INVISIBLE (-3650 1925);
FORCEPROP 2 LAST BOM_COST PVPP_KLM_VR
J 0
(-3900 1925);
DISPLAY 1.042553 (-3900 1925);
PAINT WHITE (-3900 1925);
DISPLAY INVISIBLE (-3900 1925);
FORCEPROP 1 LAST BODY_TYPE PLUMBING
J 0
(-3045 1732);
DISPLAY 0.340426 (-3045 1732);
PAINT GREEN (-3045 1732);
DISPLAY INVISIBLE (-3045 1732);
FORCEPROP 1 LAST HDL_POWER GND
J 0
(-3000 2000);
DISPLAY 0.893617 (-3000 2000);
PAINT GREEN (-3000 2000);
DISPLAY INVISIBLE (-3000 2000);
FORCEADD GND..1
(-2450 2900);
FORCEPROP 3 LASTPIN (-2450 2950) SIG_NAME GND\g
J 0
(-2440 2960);
DISPLAY 0.659574 (-2440 2960);
PAINT MONO (-2440 2960);
DISPLAY INVISIBLE (-2440 2960);
FORCEPROP 1 LAST VOLTAGE 0
J 0
(-2450 2975);
PAINT SKYBLUE (-2450 2975);
DISPLAY INVISIBLE (-2450 2975);
FORCEPROP 2 LAST CDS_LIB mstr_symbols
J 0
(-2450 2975);
PAINT MONO (-2450 2975);
DISPLAY INVISIBLE (-2450 2975);
FORCEPROP 1 LAST SIZE 1B
J 0
(-2375 2925);
DISPLAY 0.893617 (-2375 2925);
PAINT GREEN (-2375 2925);
DISPLAY INVISIBLE (-2375 2925);
FORCEPROP 1 LAST PATH I207
J 0
(-2375 2900);
DISPLAY 0.872340 (-2375 2900);
PAINT AQUA (-2375 2900);
DISPLAY INVISIBLE (-2375 2900);
FORCEPROP 2 LAST ROOM PVPP_KLM_VR
J 0
(-3100 3050);
PAINT GREEN (-3100 3050);
DISPLAY INVISIBLE (-3100 3050);
FORCEPROP 2 LAST BOM_COST PVPP_KLM_VR
J 0
(-3350 3050);
DISPLAY 1.042553 (-3350 3050);
PAINT WHITE (-3350 3050);
DISPLAY INVISIBLE (-3350 3050);
FORCEPROP 1 LAST BODY_TYPE PLUMBING
J 0
(-2495 2857);
DISPLAY 0.340426 (-2495 2857);
PAINT GREEN (-2495 2857);
DISPLAY INVISIBLE (-2495 2857);
FORCEPROP 1 LAST HDL_POWER GND
J 0
(-2450 3125);
DISPLAY 0.893617 (-2450 3125);
PAINT GREEN (-2450 3125);
DISPLAY INVISIBLE (-2450 3125);
FORCEADD RES..2
(-2450 3100);
FORCEPROP 1 LASTPIN (-2450 3200) $PN 1
J 0
(-2445 3162);
DISPLAY 0.617021 (-2445 3162);
PAINT WHITE (-2445 3162);
FORCEPROP 1 LAST LOCATION R4F6
J 0
(-2330 3150);
DISPLAY 0.617021 (-2330 3150);
PAINT AQUA (-2330 3150);
FORCEPROP 1 LAST MATERIAL EMPTY
J 0
(-2335 3075);
DISPLAY 0.617021 (-2335 3075);
PAINT RED (-2335 3075);
FORCEPROP 1 LASTPIN (-2450 3000) $PN 2
J 0
(-2445 3010);
DISPLAY 0.617021 (-2445 3010);
PAINT WHITE (-2445 3010);
FORCEPROP 1 LAST PACK_TYPE 0402
J 0
(-2035 3075);
DISPLAY 0.617021 (-2035 3075);
PAINT SKYBLUE (-2035 3075);
FORCEPROP 1 LAST TOLERANCE 5%
J 0
(-2105 3150);
DISPLAY 0.617021 (-2105 3150);
PAINT SKYBLUE (-2105 3150);
FORCEPROP 1 LAST VALUE 2.2
J 0
(-2205 3150);
DISPLAY 0.617021 (-2205 3150);
PAINT SKYBLUE (-2205 3150);
FORCEPROP 1 LAST WATTAGE 1/16W
J 0
(-2185 3075);
DISPLAY 0.617021 (-2185 3075);
PAINT SKYBLUE (-2185 3075);
FORCEPROP 1 LAST PART_NUMBER G21497-016
J 0
(-2335 3000);
DISPLAY 0.617021 (-2335 3000);
PAINT BLUE (-2335 3000);
FORCEPROP 2 LAST REUSE_ID 29
J 0
(-2400 3325);
DISPLAY 1.042553 (-2400 3325);
PAINT ORANGE (-2400 3325);
DISPLAY INVISIBLE (-2400 3325);
FORCEPROP 2 LAST CDS_SEC 1
J 0
(-2400 3325);
DISPLAY 1.042553 (-2400 3325);
PAINT ORANGE (-2400 3325);
DISPLAY INVISIBLE (-2400 3325);
FORCEPROP 2 LAST BOM_COST PVPP_KLM_VR
J 0
(-2400 3275);
DISPLAY 1.042553 (-2400 3275);
PAINT WHITE (-2400 3275);
DISPLAY INVISIBLE (-2400 3275);
FORCEPROP 2 LAST $SEC 1
J 0
(-2400 3325);
DISPLAY 0.680851 (-2400 3325);
PAINT MONO (-2400 3325);
DISPLAY INVISIBLE (-2400 3325);
FORCEPROP 1 LAST PATH I208
J 0
(-2400 3275);
DISPLAY 0.978723 (-2400 3275);
PAINT WHITE (-2400 3275);
DISPLAY INVISIBLE (-2400 3275);
FORCEPROP 2 LAST ROOM PVPP_KLM_VR
J 0
(-2400 3250);
PAINT GREEN (-2400 3250);
DISPLAY INVISIBLE (-2400 3250);
FORCEPROP 2 LAST CDS_LOCATION R4F6
J 0
(-2405 3200);
DISPLAY 0.617021 (-2405 3200);
PAINT AQUA (-2405 3200);
DISPLAY INVISIBLE (-2405 3200);
FORCEPROP 2 LAST CDS_LIB mstr_discrete
J 0
(-2450 3100);
PAINT MONO (-2450 3100);
DISPLAY INVISIBLE (-2450 3100);
FORCEADD CAP..1
(-2450 3475);
FORCEPROP 1 LAST VALUE 3300PF
J 0
(-2325 3525);
DISPLAY 0.617021 (-2325 3525);
PAINT SKYBLUE (-2325 3525);
FORCEPROP 1 LAST VOLTAGE 50V
J 0
(-2325 3475);
DISPLAY 0.617021 (-2325 3475);
PAINT SKYBLUE (-2325 3475);
FORCEPROP 1 LAST LOCATION C4F12
J 0
(-2325 3575);
DISPLAY 0.617021 (-2325 3575);
PAINT AQUA (-2325 3575);
FORCEPROP 1 LAST MATERIAL EMPTY
J 0
(-2225 3450);
DISPLAY 0.617021 (-2225 3450);
PAINT RED (-2225 3450);
FORCEPROP 1 LAST PART_NUMBER A36096-091
J 0
(-2325 3325);
DISPLAY 0.617021 (-2325 3325);
PAINT BLUE (-2325 3325);
FORCEPROP 1 LAST PACK_TYPE 0402LF
J 0
(-2325 3375);
DISPLAY 0.617021 (-2325 3375);
PAINT SKYBLUE (-2325 3375);
FORCEPROP 1 LAST TOLERANCE 10%
J 0
(-2325 3425);
DISPLAY 0.617021 (-2325 3425);
PAINT SKYBLUE (-2325 3425);
FORCEPROP 1 LASTPIN (-2450 3375) $PN 2
J 0
(-2440 3355);
DISPLAY 0.617021 (-2440 3355);
PAINT WHITE (-2440 3355);
FORCEPROP 1 LASTPIN (-2450 3575) $PN 1
J 0
(-2440 3555);
DISPLAY 0.617021 (-2440 3555);
PAINT WHITE (-2440 3555);
FORCEPROP 2 LAST BOM_COST PVPP_KLM_VR
J 0
(-2400 3625);
DISPLAY 1.042553 (-2400 3625);
PAINT WHITE (-2400 3625);
DISPLAY INVISIBLE (-2400 3625);
FORCEPROP 2 LAST REUSE_ID 26
J 0
(-2400 3675);
DISPLAY 1.042553 (-2400 3675);
PAINT ORANGE (-2400 3675);
DISPLAY INVISIBLE (-2400 3675);
FORCEPROP 2 LAST CDS_SEC 1
J 0
(-2400 3675);
DISPLAY 1.042553 (-2400 3675);
PAINT ORANGE (-2400 3675);
DISPLAY INVISIBLE (-2400 3675);
FORCEPROP 2 LAST $SEC 1
J 0
(-2400 3675);
DISPLAY 0.680851 (-2400 3675);
PAINT MONO (-2400 3675);
DISPLAY INVISIBLE (-2400 3675);
FORCEPROP 2 LAST CDS_LOCATION C4F12
J 0
(-2350 3575);
DISPLAY 0.617021 (-2350 3575);
PAINT AQUA (-2350 3575);
DISPLAY INVISIBLE (-2350 3575);
FORCEPROP 1 LAST PATH I209
J 0
(-2400 3625);
DISPLAY 0.978723 (-2400 3625);
PAINT WHITE (-2400 3625);
DISPLAY INVISIBLE (-2400 3625);
FORCEPROP 2 LAST ROOM PVPP_KLM_VR
J 0
(-2400 3600);
PAINT GREEN (-2400 3600);
DISPLAY INVISIBLE (-2400 3600);
FORCEPROP 2 LAST CDS_LIB mstr_discrete
J 0
(-2450 3475);
PAINT MONO (-2450 3475);
DISPLAY INVISIBLE (-2450 3475);
FORCEADD GND..1
(-2000 3325);
FORCEPROP 3 LASTPIN (-2000 3375) SIG_NAME GND\g
J 0
(-1990 3385);
DISPLAY 0.659574 (-1990 3385);
PAINT MONO (-1990 3385);
DISPLAY INVISIBLE (-1990 3385);
FORCEPROP 1 LAST VOLTAGE 0
J 0
(-2000 3325);
PAINT SKYBLUE (-2000 3325);
DISPLAY INVISIBLE (-2000 3325);
FORCEPROP 1 LAST SIZE 1B
J 0
(-1925 3275);
DISPLAY 0.872340 (-1925 3275);
PAINT GREEN (-1925 3275);
DISPLAY INVISIBLE (-1925 3275);
FORCEPROP 2 LAST CDS_LIB mstr_symbols
J 0
(-2000 3325);
PAINT MONO (-2000 3325);
DISPLAY INVISIBLE (-2000 3325);
FORCEPROP 1 LAST PATH I210
J 0
(-1925 3325);
DISPLAY 0.872340 (-1925 3325);
PAINT AQUA (-1925 3325);
DISPLAY INVISIBLE (-1925 3325);
FORCEPROP 2 LAST ROOM PVPP_KLM_VR
J 0
(-2575 3400);
DISPLAY 1.042553 (-2575 3400);
PAINT GREEN (-2575 3400);
DISPLAY INVISIBLE (-2575 3400);
FORCEPROP 2 LAST BOM_COST PVPP_KLM_VR
J 0
(-2850 3400);
DISPLAY 1.042553 (-2850 3400);
PAINT WHITE (-2850 3400);
DISPLAY INVISIBLE (-2850 3400);
FORCEPROP 1 LAST BODY_TYPE PLUMBING
J 0
(-2045 3282);
DISPLAY 0.340426 (-2045 3282);
PAINT GREEN (-2045 3282);
DISPLAY INVISIBLE (-2045 3282);
FORCEPROP 1 LAST HDL_POWER GND
J 0
(-2000 3475);
DISPLAY 0.872340 (-2000 3475);
PAINT GREEN (-2000 3475);
DISPLAY INVISIBLE (-2000 3475);
FORCEADD RES..2
(-2000 3525);
FORCEPROP 1 LAST VALUE 120.0
J 0
(-1955 3600);
DISPLAY 0.617021 (-1955 3600);
PAINT SKYBLUE (-1955 3600);
FORCEPROP 1 LAST TOLERANCE 1%
J 0
(-1955 3550);
DISPLAY 0.617021 (-1955 3550);
PAINT SKYBLUE (-1955 3550);
FORCEPROP 1 LAST LOCATION R4G6
J 0
(-1955 3650);
DISPLAY 0.617021 (-1955 3650);
PAINT AQUA (-1955 3650);
FORCEPROP 1 LASTPIN (-2000 3625) $PN 1
J 0
(-1995 3587);
DISPLAY 0.617021 (-1995 3587);
PAINT WHITE (-1995 3587);
FORCEPROP 1 LAST WATTAGE 1/10W
J 0
(-1960 3500);
DISPLAY 0.617021 (-1960 3500);
PAINT SKYBLUE (-1960 3500);
FORCEPROP 1 LASTPIN (-2000 3425) $PN 2
J 0
(-1995 3435);
DISPLAY 0.617021 (-1995 3435);
PAINT WHITE (-1995 3435);
FORCEPROP 1 LAST PACK_TYPE 0603
J 0
(-1960 3350);
DISPLAY 0.617021 (-1960 3350);
PAINT SKYBLUE (-1960 3350);
FORCEPROP 1 LAST MATERIAL CHIP
J 0
(-1960 3450);
DISPLAY 0.617021 (-1960 3450);
PAINT SKYBLUE (-1960 3450);
FORCEPROP 1 LAST PART_NUMBER G22026-003
J 0
(-1960 3400);
DISPLAY 0.617021 (-1960 3400);
PAINT BLUE (-1960 3400);
FORCEPROP 2 LAST REUSE_ID 34
J 0
(-1950 3750);
DISPLAY 1.042553 (-1950 3750);
PAINT ORANGE (-1950 3750);
DISPLAY INVISIBLE (-1950 3750);
FORCEPROP 2 LAST CDS_SEC 1
J 0
(-1950 3750);
DISPLAY 1.042553 (-1950 3750);
PAINT ORANGE (-1950 3750);
DISPLAY INVISIBLE (-1950 3750);
FORCEPROP 2 LAST $SEC 1
J 0
(-1950 3750);
DISPLAY 0.680851 (-1950 3750);
PAINT MONO (-1950 3750);
DISPLAY INVISIBLE (-1950 3750);
FORCEPROP 2 LAST BOM_COST PVPP_KLM_VR
J 0
(-1955 3705);
DISPLAY 1.042553 (-1955 3705);
PAINT WHITE (-1955 3705);
DISPLAY INVISIBLE (-1955 3705);
FORCEPROP 1 LAST PATH I211
J 0
(-1950 3700);
DISPLAY 0.978723 (-1950 3700);
PAINT WHITE (-1950 3700);
DISPLAY INVISIBLE (-1950 3700);
FORCEPROP 2 LAST ROOM PVPP_KLM_VR
J 0
(-1955 3680);
PAINT GREEN (-1955 3680);
DISPLAY INVISIBLE (-1955 3680);
FORCEPROP 2 LAST CDS_LOCATION R4G6
J 0
(-1955 3650);
DISPLAY 0.617021 (-1955 3650);
PAINT AQUA (-1955 3650);
DISPLAY INVISIBLE (-1955 3650);
FORCEPROP 2 LAST CDS_LIB mstr_discrete
J 0
(-2000 3525);
PAINT MONO (-2000 3525);
DISPLAY INVISIBLE (-2000 3525);
FORCEADD GND..1
(-1700 3175);
FORCEPROP 3 LASTPIN (-1700 3225) SIG_NAME GND\g
J 0
(-1690 3235);
DISPLAY 0.659574 (-1690 3235);
PAINT MONO (-1690 3235);
DISPLAY INVISIBLE (-1690 3235);
FORCEPROP 2 LAST BOM_COST PVPP_KLM_VR
J 0
(-2550 3250);
DISPLAY 1.042553 (-2550 3250);
PAINT WHITE (-2550 3250);
DISPLAY INVISIBLE (-2550 3250);
FORCEPROP 2 LAST ROOM PVPP_KLM_VR
J 0
(-2275 3250);
DISPLAY 1.042553 (-2275 3250);
PAINT GREEN (-2275 3250);
DISPLAY INVISIBLE (-2275 3250);
FORCEPROP 1 LAST SIZE 1B
J 0
(-1625 3125);
DISPLAY 0.872340 (-1625 3125);
PAINT GREEN (-1625 3125);
DISPLAY INVISIBLE (-1625 3125);
FORCEPROP 1 LAST PATH I216
J 0
(-1625 3175);
DISPLAY 0.872340 (-1625 3175);
PAINT AQUA (-1625 3175);
DISPLAY INVISIBLE (-1625 3175);
FORCEPROP 2 LAST CDS_LIB mstr_symbols
J 0
(-1700 3175);
PAINT MONO (-1700 3175);
DISPLAY INVISIBLE (-1700 3175);
FORCEPROP 1 LAST VOLTAGE 0
J 0
(-1700 3175);
PAINT SKYBLUE (-1700 3175);
DISPLAY INVISIBLE (-1700 3175);
FORCEPROP 1 LAST BODY_TYPE PLUMBING
J 0
(-1745 3132);
DISPLAY 0.340426 (-1745 3132);
PAINT GREEN (-1745 3132);
DISPLAY INVISIBLE (-1745 3132);
FORCEPROP 1 LAST HDL_POWER GND
J 0
(-1700 3325);
DISPLAY 0.872340 (-1700 3325);
PAINT GREEN (-1700 3325);
DISPLAY INVISIBLE (-1700 3325);
FORCEADD CAPP..1
(-1700 3500);
FORCEPROP 1 LASTPIN (-1700 3400) $PN 2
J 0
(-1690 3385);
DISPLAY 0.617021 (-1690 3385);
PAINT WHITE (-1690 3385);
FORCEPROP 1 LASTPIN (-1700 3600) $PN 1
J 0
(-1690 3585);
DISPLAY 0.617021 (-1690 3585);
PAINT WHITE (-1690 3585);
FORCEPROP 1 LAST LOCATION C4F7
J 0
(-1650 3650);
DISPLAY 0.617021 (-1650 3650);
PAINT AQUA (-1650 3650);
FORCEPROP 1 LAST VALUE 330UF
J 0
(-1650 3600);
DISPLAY 0.617021 (-1650 3600);
PAINT SKYBLUE (-1650 3600);
FORCEPROP 1 LAST TOLERANCE 20%
J 0
(-1650 3550);
DISPLAY 0.617021 (-1650 3550);
PAINT SKYBLUE (-1650 3550);
FORCEPROP 1 LAST VOLTAGE 6.3V
J 0
(-1650 3500);
DISPLAY 0.617021 (-1650 3500);
PAINT SKYBLUE (-1650 3500);
FORCEPROP 1 LAST MATERIAL POSCAP
J 0
(-1650 3450);
DISPLAY 0.617021 (-1650 3450);
PAINT SKYBLUE (-1650 3450);
FORCEPROP 1 LAST PACK_TYPE 7343LF
J 0
(-1650 3400);
DISPLAY 0.617021 (-1650 3400);
PAINT SKYBLUE (-1650 3400);
FORCEPROP 1 LAST PART_NUMBER 724613-042
J 0
(-1650 3350);
DISPLAY 0.617021 (-1650 3350);
PAINT BLUE (-1650 3350);
FORCEPROP 0 LAST GROUP PWR_BULK_CAP
J 0
(-1635 3301);
DISPLAY 0.638298 (-1635 3301);
PAINT BROWN (-1635 3301);
DISPLAY BOTH (-1635 3301);
FORCEPROP 2 LAST ROOM PVPP_KLM_VR
J 0
(-1700 3500);
PAINT GREEN (-1700 3500);
DISPLAY INVISIBLE (-1700 3500);
FORCEPROP 2 LAST CDS_LIB mstr_discrete
J 0
(-1700 3500);
PAINT MONO (-1700 3500);
DISPLAY INVISIBLE (-1700 3500);
FORCEPROP 2 LAST BOM_COST PVPP_KLM_VR
J 0
(-1700 3500);
DISPLAY 0.659574 (-1700 3500);
PAINT WHITE (-1700 3500);
DISPLAY INVISIBLE (-1700 3500);
FORCEPROP 2 LAST REUSE_ID 28
J 0
(-1650 3700);
DISPLAY 1.042553 (-1650 3700);
PAINT ORANGE (-1650 3700);
DISPLAY INVISIBLE (-1650 3700);
FORCEPROP 2 LAST CDS_SEC 1
J 0
(-1650 3700);
DISPLAY 1.042553 (-1650 3700);
PAINT ORANGE (-1650 3700);
DISPLAY INVISIBLE (-1650 3700);
FORCEPROP 2 LAST $SEC 1
J 0
(-1650 3700);
DISPLAY 0.680851 (-1650 3700);
PAINT MONO (-1650 3700);
DISPLAY INVISIBLE (-1650 3700);
FORCEPROP 2 LAST CDS_LOCATION C4F7
J 0
(-1650 3600);
DISPLAY 0.617021 (-1650 3600);
PAINT AQUA (-1650 3600);
DISPLAY INVISIBLE (-1650 3600);
FORCEPROP 1 LAST PATH I217
J 0
(-1650 3650);
DISPLAY 0.978723 (-1650 3650);
PAINT ORANGE (-1650 3650);
DISPLAY INVISIBLE (-1650 3650);
FORCEADD GND..1
(-1075 3325);
FORCEPROP 3 LASTPIN (-1075 3375) SIG_NAME GND\g
J 0
(-1065 3385);
DISPLAY 0.659574 (-1065 3385);
PAINT MONO (-1065 3385);
DISPLAY INVISIBLE (-1065 3385);
FORCEPROP 1 LAST SIZE 1B
J 0
(-1000 3275);
DISPLAY 0.872340 (-1000 3275);
PAINT GREEN (-1000 3275);
DISPLAY INVISIBLE (-1000 3275);
FORCEPROP 1 LAST PATH I220
J 0
(-1000 3325);
DISPLAY 0.872340 (-1000 3325);
PAINT AQUA (-1000 3325);
DISPLAY INVISIBLE (-1000 3325);
FORCEPROP 1 LAST VOLTAGE 0
J 0
(-1075 3325);
PAINT SKYBLUE (-1075 3325);
DISPLAY INVISIBLE (-1075 3325);
FORCEPROP 2 LAST CDS_LIB mstr_symbols
J 0
(-1075 3325);
PAINT MONO (-1075 3325);
DISPLAY INVISIBLE (-1075 3325);
FORCEPROP 2 LAST ROOM PVPP_KLM_VR
J 0
(-1650 3400);
DISPLAY 1.042553 (-1650 3400);
PAINT GREEN (-1650 3400);
DISPLAY INVISIBLE (-1650 3400);
FORCEPROP 2 LAST BOM_COST PVPP_KLM_VR
J 0
(-1925 3400);
DISPLAY 1.042553 (-1925 3400);
PAINT WHITE (-1925 3400);
DISPLAY INVISIBLE (-1925 3400);
FORCEPROP 1 LAST BODY_TYPE PLUMBING
J 0
(-1120 3282);
DISPLAY 0.340426 (-1120 3282);
PAINT GREEN (-1120 3282);
DISPLAY INVISIBLE (-1120 3282);
FORCEPROP 1 LAST HDL_POWER GND
J 0
(-1075 3475);
DISPLAY 0.872340 (-1075 3475);
PAINT GREEN (-1075 3475);
DISPLAY INVISIBLE (-1075 3475);
FORCEADD CAP..1
(-1075 3525);
FORCEPROP 1 LAST MATERIAL X6S
J 0
(-1025 3425);
DISPLAY 0.617021 (-1025 3425);
PAINT SKYBLUE (-1025 3425);
FORCEPROP 1 LASTPIN (-1075 3625) $PN 1
J 0
(-1065 3605);
DISPLAY 0.617021 (-1065 3605);
PAINT WHITE (-1065 3605);
FORCEPROP 1 LASTPIN (-1075 3425) $PN 2
J 0
(-1065 3405);
DISPLAY 0.617021 (-1065 3405);
PAINT WHITE (-1065 3405);
FORCEPROP 1 LAST TOLERANCE 20%
J 0
(-1025 3475);
DISPLAY 0.617021 (-1025 3475);
PAINT SKYBLUE (-1025 3475);
FORCEPROP 1 LAST VOLTAGE 4V
J 0
(-1025 3525);
DISPLAY 0.617021 (-1025 3525);
PAINT SKYBLUE (-1025 3525);
FORCEPROP 1 LAST VALUE 47UF
J 0
(-1025 3575);
DISPLAY 0.617021 (-1025 3575);
PAINT SKYBLUE (-1025 3575);
FORCEPROP 1 LAST LOCATION C6U3
J 0
(-1025 3625);
DISPLAY 0.617021 (-1025 3625);
PAINT AQUA (-1025 3625);
FORCEPROP 1 LAST PART_NUMBER C95333-006
J 0
(-1025 3375);
DISPLAY 0.617021 (-1025 3375);
PAINT BLUE (-1025 3375);
FORCEPROP 1 LAST PACK_TYPE 0805
J 0
(-1025 3325);
DISPLAY 0.617021 (-1025 3325);
PAINT SKYBLUE (-1025 3325);
FORCEPROP 0 LAST GROUP PWR_MLCC_CAP
J 0
(-1069 3212);
DISPLAY 0.638298 (-1069 3212);
PAINT BROWN (-1069 3212);
DISPLAY BOTH (-1069 3212);
FORCEPROP 1 LAST PATH I221
J 0
(-1025 3675);
DISPLAY 0.978723 (-1025 3675);
PAINT WHITE (-1025 3675);
DISPLAY INVISIBLE (-1025 3675);
FORCEPROP 2 LAST CDS_LOCATION C6U3
J 0
(-1025 3625);
DISPLAY 0.617021 (-1025 3625);
PAINT AQUA (-1025 3625);
DISPLAY INVISIBLE (-1025 3625);
FORCEPROP 2 LAST $SEC 1
J 0
(-1025 3725);
DISPLAY 0.680851 (-1025 3725);
PAINT MONO (-1025 3725);
DISPLAY INVISIBLE (-1025 3725);
FORCEPROP 2 LAST CDS_SEC 1
J 0
(-1025 3725);
DISPLAY 1.042553 (-1025 3725);
PAINT ORANGE (-1025 3725);
DISPLAY INVISIBLE (-1025 3725);
FORCEPROP 2 LAST REUSE_ID 33
J 0
(-1025 3725);
DISPLAY 1.042553 (-1025 3725);
PAINT ORANGE (-1025 3725);
DISPLAY INVISIBLE (-1025 3725);
FORCEPROP 2 LAST ROOM PVPP_KLM_VR
J 0
(-1075 3525);
PAINT GREEN (-1075 3525);
DISPLAY INVISIBLE (-1075 3525);
FORCEPROP 2 LAST CDS_LIB mstr_discrete
J 0
(-1075 3525);
PAINT MONO (-1075 3525);
DISPLAY INVISIBLE (-1075 3525);
FORCEPROP 2 LAST BOM_COST PVPP_KLM_VR
J 0
(-1075 3525);
PAINT WHITE (-1075 3525);
DISPLAY INVISIBLE (-1075 3525);
FORCEADD GND..1
(-775 3325);
FORCEPROP 3 LASTPIN (-775 3375) SIG_NAME GND\g
J 0
(-765 3385);
DISPLAY 0.659574 (-765 3385);
PAINT MONO (-765 3385);
DISPLAY INVISIBLE (-765 3385);
FORCEPROP 2 LAST BOM_COST PVPP_KLM_VR
J 0
(-1625 3400);
DISPLAY 1.042553 (-1625 3400);
PAINT WHITE (-1625 3400);
DISPLAY INVISIBLE (-1625 3400);
FORCEPROP 2 LAST ROOM PVPP_KLM_VR
J 0
(-1350 3400);
DISPLAY 1.042553 (-1350 3400);
PAINT GREEN (-1350 3400);
DISPLAY INVISIBLE (-1350 3400);
FORCEPROP 2 LAST CDS_LIB mstr_symbols
J 0
(-775 3325);
PAINT MONO (-775 3325);
DISPLAY INVISIBLE (-775 3325);
FORCEPROP 1 LAST VOLTAGE 0
J 0
(-775 3325);
PAINT SKYBLUE (-775 3325);
DISPLAY INVISIBLE (-775 3325);
FORCEPROP 1 LAST PATH I222
J 0
(-700 3325);
DISPLAY 0.872340 (-700 3325);
PAINT AQUA (-700 3325);
DISPLAY INVISIBLE (-700 3325);
FORCEPROP 1 LAST SIZE 1B
J 0
(-700 3275);
DISPLAY 0.872340 (-700 3275);
PAINT GREEN (-700 3275);
DISPLAY INVISIBLE (-700 3275);
FORCEPROP 1 LAST BODY_TYPE PLUMBING
J 0
(-820 3282);
DISPLAY 0.340426 (-820 3282);
PAINT GREEN (-820 3282);
DISPLAY INVISIBLE (-820 3282);
FORCEPROP 1 LAST HDL_POWER GND
J 0
(-775 3475);
DISPLAY 0.872340 (-775 3475);
PAINT GREEN (-775 3475);
DISPLAY INVISIBLE (-775 3475);
FORCEADD CAP..1
(-775 3525);
FORCEPROP 1 LASTPIN (-775 3425) $PN 2
J 0
(-765 3405);
DISPLAY 0.617021 (-765 3405);
PAINT WHITE (-765 3405);
FORCEPROP 1 LAST MATERIAL X6S
J 0
(-725 3425);
DISPLAY 0.617021 (-725 3425);
PAINT SKYBLUE (-725 3425);
FORCEPROP 1 LAST VOLTAGE 4V
J 0
(-725 3525);
DISPLAY 0.617021 (-725 3525);
PAINT SKYBLUE (-725 3525);
FORCEPROP 1 LAST VALUE 47UF
J 0
(-725 3575);
DISPLAY 0.617021 (-725 3575);
PAINT SKYBLUE (-725 3575);
FORCEPROP 1 LAST PACK_TYPE 0805
J 0
(-725 3325);
DISPLAY 0.617021 (-725 3325);
PAINT SKYBLUE (-725 3325);
FORCEPROP 1 LASTPIN (-775 3625) $PN 1
J 0
(-765 3605);
DISPLAY 0.617021 (-765 3605);
PAINT WHITE (-765 3605);
FORCEPROP 1 LAST LOCATION C6U2
J 0
(-725 3625);
DISPLAY 0.617021 (-725 3625);
PAINT AQUA (-725 3625);
FORCEPROP 1 LAST PART_NUMBER C95333-006
J 0
(-725 3375);
DISPLAY 0.617021 (-725 3375);
PAINT BLUE (-725 3375);
FORCEPROP 0 LAST GROUP PWR_MLCC_CAP
J 0
(-769 3262);
DISPLAY 0.638298 (-769 3262);
PAINT BROWN (-769 3262);
DISPLAY BOTH (-769 3262);
FORCEPROP 1 LAST TOLERANCE 20%
J 0
(-725 3475);
DISPLAY 0.617021 (-725 3475);
PAINT SKYBLUE (-725 3475);
FORCEPROP 2 LAST BOM_COST PVPP_KLM_VR
J 0
(-775 3525);
PAINT WHITE (-775 3525);
DISPLAY INVISIBLE (-775 3525);
FORCEPROP 2 LAST CDS_LIB mstr_discrete
J 0
(-775 3525);
PAINT MONO (-775 3525);
DISPLAY INVISIBLE (-775 3525);
FORCEPROP 2 LAST ROOM PVPP_KLM_VR
J 0
(-775 3525);
PAINT GREEN (-775 3525);
DISPLAY INVISIBLE (-775 3525);
FORCEPROP 1 LAST PATH I223
J 0
(-725 3675);
DISPLAY 0.978723 (-725 3675);
PAINT WHITE (-725 3675);
DISPLAY INVISIBLE (-725 3675);
FORCEPROP 2 LAST CDS_LOCATION C6U2
J 0
(-725 3625);
DISPLAY 0.617021 (-725 3625);
PAINT AQUA (-725 3625);
DISPLAY INVISIBLE (-725 3625);
FORCEPROP 2 LAST $SEC 1
J 0
(-725 3725);
DISPLAY 0.680851 (-725 3725);
PAINT MONO (-725 3725);
DISPLAY INVISIBLE (-725 3725);
FORCEPROP 2 LAST CDS_SEC 1
J 0
(-725 3725);
DISPLAY 1.042553 (-725 3725);
PAINT ORANGE (-725 3725);
DISPLAY INVISIBLE (-725 3725);
FORCEPROP 2 LAST REUSE_ID 33
J 0
(-725 3725);
DISPLAY 1.042553 (-725 3725);
PAINT ORANGE (-725 3725);
DISPLAY INVISIBLE (-725 3725);
FORCEADD CAP..2
R 2
(-3300 4050);
FORCEPROP 1 LAST LOCATION C4G26
J 1
(-3300 4150);
DISPLAY 0.617021 (-3300 4150);
PAINT AQUA (-3300 4150);
FORCEPROP 1 LAST PART_NUMBER 602433-020
J 1
(-3300 4100);
DISPLAY 0.617021 (-3300 4100);
PAINT BLUE (-3300 4100);
FORCEPROP 1 LASTPIN (-3200 4050) $PN 1
J 2
(-3190 4065);
DISPLAY 0.617021 (-3190 4065);
PAINT WHITE (-3190 4065);
FORCEPROP 1 LAST TOLERANCE 10%
J 0
(-3300 3900);
DISPLAY 0.617021 (-3300 3900);
PAINT SKYBLUE (-3300 3900);
FORCEPROP 1 LAST VALUE 0.1UF
J 0
(-3300 3950);
DISPLAY 0.617021 (-3300 3950);
PAINT SKYBLUE (-3300 3950);
FORCEPROP 1 LAST MATERIAL X7R
J 2
(-3300 3900);
DISPLAY 0.617021 (-3300 3900);
PAINT SKYBLUE (-3300 3900);
FORCEPROP 1 LAST VOLTAGE 25V
J 2
(-3300 3950);
DISPLAY 0.617021 (-3300 3950);
PAINT SKYBLUE (-3300 3950);
FORCEPROP 1 LAST PACK_TYPE 0603LF
J 1
(-3300 3850);
DISPLAY 0.617021 (-3300 3850);
PAINT SKYBLUE (-3300 3850);
FORCEPROP 1 LASTPIN (-3400 4050) $PN 2
J 2
(-3385 4065);
DISPLAY 0.617021 (-3385 4065);
PAINT WHITE (-3385 4065);
FORCEPROP 2 LAST REUSE_ID 27
J 0
(-3300 4300);
DISPLAY 1.042553 (-3300 4300);
PAINT ORANGE (-3300 4300);
DISPLAY INVISIBLE (-3300 4300);
FORCEPROP 0 LAST SPOF TRUE
J 0
(-3300 4250);
DISPLAY 1.021277 (-3300 4250);
PAINT ORANGE (-3300 4250);
DISPLAY INVISIBLE (-3300 4250);
FORCEPROP 2 LAST BOM_COST PVPP_KLM_VR
J 0
(-3345 4210);
DISPLAY 1.042553 (-3345 4210);
PAINT WHITE (-3345 4210);
DISPLAY INVISIBLE (-3345 4210);
FORCEPROP 2 LAST CDS_SEC 1
J 0
(-3345 4260);
DISPLAY 1.042553 (-3345 4260);
PAINT ORANGE (-3345 4260);
DISPLAY INVISIBLE (-3345 4260);
FORCEPROP 2 LAST $SEC 1
J 0
(-3300 4300);
DISPLAY 0.680851 (-3300 4300);
PAINT MONO (-3300 4300);
DISPLAY INVISIBLE (-3300 4300);
FORCEPROP 1 LAST PATH I224
J 2
(-3300 4250);
DISPLAY 0.978723 (-3300 4250);
PAINT WHITE (-3300 4250);
DISPLAY INVISIBLE (-3300 4250);
FORCEPROP 2 LAST ROOM PVPP_KLM_VR
J 2
(-3300 4175);
DISPLAY 0.765957 (-3300 4175);
PAINT GREEN (-3300 4175);
DISPLAY INVISIBLE (-3300 4175);
FORCEPROP 2 LAST CDS_LIB mstr_discrete
J 0
(-3300 4050);
PAINT MONO (-3300 4050);
DISPLAY INVISIBLE (-3300 4050);
FORCEADD NCP3232L..1
(-3725 2725);
FORCEPROP 1 LAST LOCATION EU4G1
J 0
(-4175 3675);
DISPLAY 0.617021 (-4175 3675);
PAINT AQUA (-4175 3675);
FORCEPROP 2 LASTPIN (-3225 3325) $PN 43
J 0
(-3215 3335);
DISPLAY 0.617021 (-3215 3335);
PAINT ORANGE (-3215 3335);
FORCEPROP 2 LASTPIN (-3225 3425) $PN 36
J 0
(-3215 3435);
DISPLAY 0.617021 (-3215 3435);
PAINT ORANGE (-3215 3435);
FORCEPROP 2 LASTPIN (-3225 3125) $PN 31
J 0
(-3215 3135);
DISPLAY 0.617021 (-3215 3135);
PAINT ORANGE (-3215 3135);
FORCEPROP 2 LASTPIN (-3225 3175) $PN 32
J 0
(-3215 3185);
DISPLAY 0.617021 (-3215 3185);
PAINT ORANGE (-3215 3185);
FORCEPROP 2 LASTPIN (-3225 3225) $PN 33
J 0
(-3215 3235);
DISPLAY 0.617021 (-3215 3235);
PAINT ORANGE (-3215 3235);
FORCEPROP 2 LASTPIN (-3225 3275) $PN 34
J 0
(-3215 3285);
DISPLAY 0.617021 (-3215 3285);
PAINT ORANGE (-3215 3285);
FORCEPROP 2 LASTPIN (-3225 2975) $PN 15
J 0
(-3215 2985);
DISPLAY 0.617021 (-3215 2985);
PAINT ORANGE (-3215 2985);
FORCEPROP 2 LASTPIN (-3225 2875) $PN 35
J 0
(-3215 2885);
DISPLAY 0.617021 (-3215 2885);
PAINT ORANGE (-3215 2885);
FORCEPROP 2 LASTPIN (-3225 2575) $PN 37
J 0
(-3215 2585);
DISPLAY 0.617021 (-3215 2585);
PAINT ORANGE (-3215 2585);
FORCEPROP 2 LASTPIN (-3225 2775) $PN 2
J 0
(-3215 2785);
DISPLAY 0.617021 (-3215 2785);
PAINT ORANGE (-3215 2785);
FORCEPROP 2 LASTPIN (-3225 2675) $PN 3
J 0
(-3215 2685);
DISPLAY 0.617021 (-3215 2685);
PAINT ORANGE (-3215 2685);
FORCEPROP 2 LASTPIN (-3225 2525) $PN 28
J 0
(-3215 2535);
DISPLAY 0.617021 (-3215 2535);
PAINT ORANGE (-3215 2535);
FORCEPROP 2 LASTPIN (-3225 2325) $PN 24
J 0
(-3215 2335);
DISPLAY 0.617021 (-3215 2335);
PAINT ORANGE (-3215 2335);
FORCEPROP 2 LASTPIN (-3225 2375) $PN 25
J 0
(-3215 2385);
DISPLAY 0.617021 (-3215 2385);
PAINT ORANGE (-3215 2385);
FORCEPROP 2 LASTPIN (-3225 2425) $PN 26
J 0
(-3215 2435);
DISPLAY 0.617021 (-3215 2435);
PAINT ORANGE (-3215 2435);
FORCEPROP 2 LASTPIN (-3225 2475) $PN 27
J 0
(-3215 2485);
DISPLAY 0.617021 (-3215 2485);
PAINT ORANGE (-3215 2485);
FORCEPROP 2 LASTPIN (-3225 2275) $PN 23
J 0
(-3215 2285);
DISPLAY 0.617021 (-3215 2285);
PAINT ORANGE (-3215 2285);
FORCEPROP 2 LASTPIN (-3225 2075) $PN 19
J 0
(-3215 2085);
DISPLAY 0.617021 (-3215 2085);
PAINT ORANGE (-3215 2085);
FORCEPROP 2 LASTPIN (-3225 2125) $PN 20
J 0
(-3215 2135);
DISPLAY 0.617021 (-3215 2135);
PAINT ORANGE (-3215 2135);
FORCEPROP 2 LASTPIN (-3225 2225) $PN 22
J 0
(-3215 2235);
DISPLAY 0.617021 (-3215 2235);
PAINT ORANGE (-3215 2235);
FORCEPROP 2 LASTPIN (-3225 2025) $PN 18
J 0
(-3215 2035);
DISPLAY 0.617021 (-3215 2035);
PAINT ORANGE (-3215 2035);
FORCEPROP 2 LASTPIN (-3225 1975) $PN 17
J 0
(-3215 1985);
DISPLAY 0.617021 (-3215 1985);
PAINT ORANGE (-3215 1985);
FORCEPROP 2 LASTPIN (-3225 1925) $PN 16
J 0
(-3215 1935);
DISPLAY 0.617021 (-3215 1935);
PAINT ORANGE (-3215 1935);
FORCEPROP 2 LASTPIN (-3225 1875) $PN 41
J 0
(-3215 1885);
DISPLAY 0.617021 (-3215 1885);
PAINT ORANGE (-3215 1885);
FORCEPROP 1 LAST PART_NUMBER H86355-001
J 0
(-4175 1725);
DISPLAY 0.617021 (-4175 1725);
PAINT BLUE (-4175 1725);
FORCEPROP 2 LASTPIN (-4225 3325) $PN 42
J 2
(-4235 3335);
DISPLAY 0.617021 (-4235 3335);
PAINT ORANGE (-4235 3335);
FORCEPROP 2 LASTPIN (-4225 3425) $PN 39
J 2
(-4235 3435);
DISPLAY 0.617021 (-4235 3435);
PAINT ORANGE (-4235 3435);
FORCEPROP 2 LASTPIN (-4225 3275) $PN 14
J 2
(-4235 3285);
DISPLAY 0.617021 (-4235 3285);
PAINT ORANGE (-4235 3285);
FORCEPROP 2 LASTPIN (-4225 3225) $PN 13
J 2
(-4235 3235);
DISPLAY 0.617021 (-4235 3235);
PAINT ORANGE (-4235 3235);
FORCEPROP 2 LASTPIN (-4225 3175) $PN 12
J 2
(-4235 3185);
DISPLAY 0.617021 (-4235 3185);
PAINT ORANGE (-4235 3185);
FORCEPROP 2 LASTPIN (-4225 3075) $PN 10
J 2
(-4235 3085);
DISPLAY 0.617021 (-4235 3085);
PAINT ORANGE (-4235 3085);
FORCEPROP 2 LASTPIN (-4225 3025) $PN 9
J 2
(-4235 3035);
DISPLAY 0.617021 (-4235 3035);
PAINT ORANGE (-4235 3035);
FORCEPROP 2 LASTPIN (-4225 2975) $PN 8
J 2
(-4235 2985);
DISPLAY 0.617021 (-4235 2985);
PAINT ORANGE (-4235 2985);
FORCEPROP 2 LASTPIN (-4225 2875) $PN 38
J 2
(-4235 2885);
DISPLAY 0.617021 (-4235 2885);
PAINT ORANGE (-4235 2885);
FORCEPROP 2 LASTPIN (-4225 2575) $PN 1
J 2
(-4235 2585);
DISPLAY 0.617021 (-4235 2585);
PAINT ORANGE (-4235 2585);
FORCEPROP 2 LASTPIN (-4225 2775) $PN 6
J 2
(-4235 2785);
DISPLAY 0.617021 (-4235 2785);
PAINT ORANGE (-4235 2785);
FORCEPROP 2 LASTPIN (-4225 2675) $PN 40
J 2
(-4235 2685);
DISPLAY 0.617021 (-4235 2685);
PAINT ORANGE (-4235 2685);
FORCEPROP 2 LASTPIN (-4225 2375) $PN 7
J 2
(-4235 2385);
DISPLAY 0.617021 (-4235 2385);
PAINT ORANGE (-4235 2385);
FORCEPROP 2 LASTPIN (-4225 2475) $PN 4
J 2
(-4235 2485);
DISPLAY 0.617021 (-4235 2485);
PAINT ORANGE (-4235 2485);
FORCEPROP 2 LASTPIN (-3225 2175) $PN 21
J 0
(-3215 2185);
DISPLAY 0.617021 (-3215 2185);
PAINT ORANGE (-3215 2185);
FORCEPROP 2 LASTPIN (-4225 3125) $PN 11
J 2
(-4235 3135);
DISPLAY 0.617021 (-4235 3135);
PAINT ORANGE (-4235 3135);
FORCEPROP 2 LASTPIN (-3225 3025) $PN 29
J 0
(-3215 3035);
DISPLAY 0.617021 (-3215 3035);
PAINT ORANGE (-3215 3035);
FORCEPROP 2 LASTPIN (-3225 3075) $PN 30
J 0
(-3215 3085);
DISPLAY 0.617021 (-3215 3085);
PAINT ORANGE (-3215 3085);
FORCEPROP 1 LAST MATERIAL IC
J 0
(-4175 3625);
DISPLAY 0.617021 (-4175 3625);
PAINT SKYBLUE (-4175 3625);
FORCEPROP 2 LASTPIN (-4225 1875) $PN 5
J 2
(-4235 1885);
DISPLAY 0.617021 (-4235 1885);
PAINT ORANGE (-4235 1885);
FORCEPROP 1 LAST PATH I225
J 0
(-3675 3625);
PAINT GREEN (-3675 3625);
DISPLAY INVISIBLE (-3675 3625);
FORCEPROP 2 LAST CDS_LIB mstr_vreg
J 0
(-3725 2725);
PAINT ORANGE (-3725 2725);
DISPLAY INVISIBLE (-3725 2725);
FORCEPROP 1 LAST CDS_LMAN_SYM_OUTLINE -450,850,450,-900
J 0
(-3725 2725);
DISPLAY 0.468085 (-3725 2725);
PAINT GREEN (-3725 2725);
DISPLAY INVISIBLE (-3725 2725);
FORCEPROP 1 LAST PACK_TYPE SM
J 0
(-4175 3725);
PAINT SKYBLUE (-4175 3725);
DISPLAY INVISIBLE (-4175 3725);
FORCEPROP 2 LAST SEC_TYPE SM
J 0
(-4175 3725);
DISPLAY 1.021277 (-4175 3725);
PAINT ORANGE (-4175 3725);
DISPLAY INVISIBLE (-4175 3725);
FORCEPROP 2 LAST SEC 1
J 0
(-4175 3725);
DISPLAY 0.680851 (-4175 3725);
PAINT MONO (-4175 3725);
DISPLAY INVISIBLE (-4175 3725);
FORCEPROP 2 LAST CDS_LOCATION EU4G1
J 0
(-4175 3675);
DISPLAY 0.617021 (-4175 3675);
PAINT AQUA (-4175 3675);
DISPLAY INVISIBLE (-4175 3675);
FORCEADD AGND_SCSI..1
(-6500 1900);
FORCEPROP 3 LASTPIN (-6500 1950) SIG_NAME AGND_PVPP_GHJ\g
J 0
(-6490 1960);
DISPLAY 0.659574 (-6490 1960);
PAINT MONO (-6490 1960);
DISPLAY INVISIBLE (-6490 1960);
FORCEPROP 1 LAST HDL_POWER AGND_PVPP_GHJ
J 1
(-6475 1825);
DISPLAY 0.617021 (-6475 1825);
PAINT GREEN (-6475 1825);
FORCEPROP 1 LAST VOLTAGE 0.0V
J 0
(-6545 1857);
DISPLAY 0.340426 (-6545 1857);
PAINT SKYBLUE (-6545 1857);
DISPLAY INVISIBLE (-6545 1857);
FORCEPROP 2 LAST BOM_COST PVPP_KLM_VR
J 0
(-6650 1850);
DISPLAY 1.042553 (-6650 1850);
PAINT WHITE (-6650 1850);
DISPLAY INVISIBLE (-6650 1850);
FORCEPROP 2 LAST CDS_LIB mstr_symbols
J 0
(-6500 1900);
PAINT MONO (-6500 1900);
DISPLAY INVISIBLE (-6500 1900);
FORCEPROP 1 LAST PATH I226
J 0
(-6425 1900);
DISPLAY 0.872340 (-6425 1900);
PAINT AQUA (-6425 1900);
DISPLAY INVISIBLE (-6425 1900);
FORCEPROP 2 LAST ROOM PVPP_KLM_VR
J 0
(-6650 1850);
DISPLAY 1.042553 (-6650 1850);
PAINT GREEN (-6650 1850);
DISPLAY INVISIBLE (-6650 1850);
FORCEPROP 1 LAST BODY_TYPE PLUMBING
J 0
(-6545 1857);
DISPLAY 0.340426 (-6545 1857);
PAINT GREEN (-6545 1857);
DISPLAY INVISIBLE (-6545 1857);
FORCEADD AGND_SCSI..1
(-5800 2050);
FORCEPROP 3 LASTPIN (-5800 2100) SIG_NAME AGND_PVPP_GHJ\g
J 0
(-5790 2110);
DISPLAY 0.659574 (-5790 2110);
PAINT MONO (-5790 2110);
DISPLAY INVISIBLE (-5790 2110);
FORCEPROP 1 LAST HDL_POWER AGND_PVPP_GHJ
J 1
(-5775 1975);
DISPLAY 0.617021 (-5775 1975);
PAINT GREEN (-5775 1975);
FORCEPROP 1 LAST PATH I227
J 0
(-5725 2050);
DISPLAY 0.872340 (-5725 2050);
PAINT AQUA (-5725 2050);
DISPLAY INVISIBLE (-5725 2050);
FORCEPROP 2 LAST CDS_LIB mstr_symbols
J 0
(-5800 2050);
PAINT MONO (-5800 2050);
DISPLAY INVISIBLE (-5800 2050);
FORCEPROP 1 LAST VOLTAGE 0.0V
J 0
(-5845 2007);
DISPLAY 0.340426 (-5845 2007);
PAINT SKYBLUE (-5845 2007);
DISPLAY INVISIBLE (-5845 2007);
FORCEPROP 2 LAST ROOM PVPP_KLM_VR
J 0
(-5950 2000);
DISPLAY 1.042553 (-5950 2000);
PAINT GREEN (-5950 2000);
DISPLAY INVISIBLE (-5950 2000);
FORCEPROP 2 LAST BOM_COST PVPP_KLM_VR
J 0
(-5950 2000);
DISPLAY 1.042553 (-5950 2000);
PAINT WHITE (-5950 2000);
DISPLAY INVISIBLE (-5950 2000);
FORCEPROP 1 LAST BODY_TYPE PLUMBING
J 0
(-5845 2007);
DISPLAY 0.340426 (-5845 2007);
PAINT GREEN (-5845 2007);
DISPLAY INVISIBLE (-5845 2007);
FORCEADD AGND_SCSI..1
(-5000 1800);
FORCEPROP 3 LASTPIN (-5000 1850) SIG_NAME AGND_PVPP_GHJ\g
J 0
(-4990 1860);
DISPLAY 0.659574 (-4990 1860);
PAINT MONO (-4990 1860);
DISPLAY INVISIBLE (-4990 1860);
FORCEPROP 1 LAST HDL_POWER AGND_PVPP_GHJ
J 1
(-4975 1725);
DISPLAY 0.617021 (-4975 1725);
PAINT GREEN (-4975 1725);
FORCEPROP 1 LAST PATH I228
J 0
(-4925 1800);
DISPLAY 0.872340 (-4925 1800);
PAINT AQUA (-4925 1800);
DISPLAY INVISIBLE (-4925 1800);
FORCEPROP 2 LAST CDS_LIB mstr_symbols
J 0
(-5000 1800);
PAINT MONO (-5000 1800);
DISPLAY INVISIBLE (-5000 1800);
FORCEPROP 1 LAST VOLTAGE 0.0V
J 0
(-5045 1757);
DISPLAY 0.340426 (-5045 1757);
PAINT SKYBLUE (-5045 1757);
DISPLAY INVISIBLE (-5045 1757);
FORCEPROP 2 LAST ROOM PVPP_KLM_VR
J 0
(-5150 1750);
DISPLAY 1.042553 (-5150 1750);
PAINT GREEN (-5150 1750);
DISPLAY INVISIBLE (-5150 1750);
FORCEPROP 2 LAST BOM_COST PVPP_KLM_VR
J 0
(-5150 1750);
DISPLAY 1.042553 (-5150 1750);
PAINT WHITE (-5150 1750);
DISPLAY INVISIBLE (-5150 1750);
FORCEPROP 1 LAST BODY_TYPE PLUMBING
J 0
(-5045 1757);
DISPLAY 0.340426 (-5045 1757);
PAINT GREEN (-5045 1757);
DISPLAY INVISIBLE (-5045 1757);
FORCEADD AGND_SCSI..1
(-4675 1250);
FORCEPROP 3 LASTPIN (-4675 1300) SIG_NAME AGND_PVPP_GHJ\g
J 0
(-4665 1310);
DISPLAY 0.659574 (-4665 1310);
PAINT MONO (-4665 1310);
DISPLAY INVISIBLE (-4665 1310);
FORCEPROP 1 LAST HDL_POWER AGND_PVPP_GHJ
J 1
(-4650 1175);
DISPLAY 0.617021 (-4650 1175);
PAINT GREEN (-4650 1175);
FORCEPROP 1 LAST PATH I229
J 0
(-4600 1250);
DISPLAY 0.872340 (-4600 1250);
PAINT AQUA (-4600 1250);
DISPLAY INVISIBLE (-4600 1250);
FORCEPROP 1 LAST VOLTAGE 0
J 0
(-4650 1275);
DISPLAY 1.021277 (-4650 1275);
PAINT SKYBLUE (-4650 1275);
DISPLAY INVISIBLE (-4650 1275);
FORCEPROP 2 LAST CDS_LIB mstr_symbols
J 0
(-4675 1250);
PAINT MONO (-4675 1250);
DISPLAY INVISIBLE (-4675 1250);
FORCEPROP 1 LAST BODY_TYPE PLUMBING
J 0
(-4720 1207);
DISPLAY 0.340426 (-4720 1207);
PAINT GREEN (-4720 1207);
DISPLAY INVISIBLE (-4720 1207);
FORCEADD AGND_SCSI..1
(-4300 1700);
FORCEPROP 3 LASTPIN (-4300 1750) SIG_NAME AGND_PVPP_GHJ\g
J 0
(-4290 1760);
DISPLAY 0.659574 (-4290 1760);
PAINT MONO (-4290 1760);
DISPLAY INVISIBLE (-4290 1760);
FORCEPROP 1 LAST HDL_POWER AGND_PVPP_GHJ
J 1
(-4275 1625);
DISPLAY 0.617021 (-4275 1625);
PAINT GREEN (-4275 1625);
FORCEPROP 1 LAST VOLTAGE 0.0V
J 0
(-4345 1657);
DISPLAY 0.340426 (-4345 1657);
PAINT SKYBLUE (-4345 1657);
DISPLAY INVISIBLE (-4345 1657);
FORCEPROP 2 LAST CDS_LIB mstr_symbols
J 0
(-4300 1700);
PAINT MONO (-4300 1700);
DISPLAY INVISIBLE (-4300 1700);
FORCEPROP 1 LAST PATH I230
J 0
(-4225 1700);
DISPLAY 0.872340 (-4225 1700);
PAINT AQUA (-4225 1700);
DISPLAY INVISIBLE (-4225 1700);
FORCEPROP 2 LAST ROOM PVPP_KLM_VR
J 0
(-4450 1650);
DISPLAY 1.042553 (-4450 1650);
PAINT GREEN (-4450 1650);
DISPLAY INVISIBLE (-4450 1650);
FORCEPROP 2 LAST BOM_COST PVPP_KLM_VR
J 0
(-4450 1650);
DISPLAY 1.042553 (-4450 1650);
PAINT WHITE (-4450 1650);
DISPLAY INVISIBLE (-4450 1650);
FORCEPROP 1 LAST BODY_TYPE PLUMBING
J 0
(-4345 1657);
DISPLAY 0.340426 (-4345 1657);
PAINT GREEN (-4345 1657);
DISPLAY INVISIBLE (-4345 1657);
FORCEADD CAP_A..1
(-5050 3325);
FORCEPROP 1 LAST VALUE 0.1UF
J 0
(-5000 3375);
DISPLAY 0.617021 (-5000 3375);
PAINT SKYBLUE (-5000 3375);
FORCEPROP 1 LAST PACK_TYPE 0402V
J 0
(-5000 3125);
DISPLAY 0.617021 (-5000 3125);
PAINT SKYBLUE (-5000 3125);
FORCEPROP 1 LAST LOCATION C6U5
J 0
(-5000 3425);
DISPLAY 0.617021 (-5000 3425);
PAINT AQUA (-5000 3425);
FORCEPROP 1 LASTPIN (-5050 3425) $PN 1
J 0
(-5040 3405);
DISPLAY 0.617021 (-5040 3405);
PAINT ORANGE (-5040 3405);
FORCEPROP 1 LAST MATERIAL X7R
J 0
(-5000 3225);
DISPLAY 0.617021 (-5000 3225);
PAINT SKYBLUE (-5000 3225);
FORCEPROP 1 LASTPIN (-5050 3225) $PN 2
J 0
(-5040 3205);
DISPLAY 0.617021 (-5040 3205);
PAINT ORANGE (-5040 3205);
FORCEPROP 1 LAST VOLTAGE 16V
J 0
(-5000 3325);
DISPLAY 0.617021 (-5000 3325);
PAINT SKYBLUE (-5000 3325);
FORCEPROP 1 LAST PART_NUMBER A36096-030
J 0
(-5000 3175);
DISPLAY 0.617021 (-5000 3175);
PAINT BLUE (-5000 3175);
FORCEPROP 1 LAST TOLERANCE 10%
J 0
(-5000 3275);
DISPLAY 0.617021 (-5000 3275);
PAINT SKYBLUE (-5000 3275);
FORCEPROP 1 LAST PATH I242
J 0
(-5000 3475);
DISPLAY 0.978723 (-5000 3475);
PAINT WHITE (-5000 3475);
DISPLAY INVISIBLE (-5000 3475);
FORCEPROP 2 LAST CDS_LOCATION C6U5
J 0
(-5000 3425);
DISPLAY 0.617021 (-5000 3425);
PAINT AQUA (-5000 3425);
DISPLAY INVISIBLE (-5000 3425);
FORCEPROP 2 LAST CDS_SEC 1
J 0
(-5000 3475);
PAINT ORANGE (-5000 3475);
DISPLAY INVISIBLE (-5000 3475);
FORCEPROP 2 LAST SEC_TYPE 0402V
J 0
(-5000 3525);
DISPLAY 1.021277 (-5000 3525);
PAINT ORANGE (-5000 3525);
DISPLAY INVISIBLE (-5000 3525);
FORCEPROP 2 LAST SEC 1
J 0
(-5000 3525);
PAINT MONO (-5000 3525);
DISPLAY INVISIBLE (-5000 3525);
FORCEPROP 2 LAST CDS_LIB dev_discrete
J 0
(-5050 3325);
PAINT ORANGE (-5050 3325);
DISPLAY INVISIBLE (-5050 3325);
FORCEADD GND..1
(-5050 3100);
FORCEPROP 3 LASTPIN (-5050 3150) SIG_NAME GND\g
J 0
(-5040 3160);
DISPLAY 0.659574 (-5040 3160);
PAINT MONO (-5040 3160);
DISPLAY INVISIBLE (-5040 3160);
FORCEPROP 1 LAST PATH I243
J 0
(-4975 3100);
DISPLAY 0.872340 (-4975 3100);
PAINT AQUA (-4975 3100);
DISPLAY INVISIBLE (-4975 3100);
FORCEPROP 1 LAST VOLTAGE 0
J 0
(-5050 3100);
PAINT SKYBLUE (-5050 3100);
DISPLAY INVISIBLE (-5050 3100);
FORCEPROP 2 LAST CDS_LIB mstr_symbols
J 0
(-5050 3100);
PAINT MONO (-5050 3100);
DISPLAY INVISIBLE (-5050 3100);
FORCEPROP 1 LAST SIZE 1B
J 0
(-4975 3050);
DISPLAY 0.872340 (-4975 3050);
PAINT GREEN (-4975 3050);
DISPLAY INVISIBLE (-4975 3050);
FORCEPROP 2 LAST ROOM PVPP_KLM_VR
J 0
(-5625 3175);
DISPLAY 1.042553 (-5625 3175);
PAINT GREEN (-5625 3175);
DISPLAY INVISIBLE (-5625 3175);
FORCEPROP 2 LAST BOM_COST PVPP_KLM_VR
J 0
(-5900 3175);
DISPLAY 1.042553 (-5900 3175);
PAINT WHITE (-5900 3175);
DISPLAY INVISIBLE (-5900 3175);
FORCEPROP 1 LAST BODY_TYPE PLUMBING
J 0
(-5095 3057);
DISPLAY 0.340426 (-5095 3057);
PAINT GREEN (-5095 3057);
DISPLAY INVISIBLE (-5095 3057);
FORCEPROP 1 LAST HDL_POWER GND
J 0
(-5050 3250);
DISPLAY 0.872340 (-5050 3250);
PAINT GREEN (-5050 3250);
DISPLAY INVISIBLE (-5050 3250);
FORCEADD AGND_SCSI..1
(-5300 2575);
FORCEPROP 3 LASTPIN (-5300 2625) SIG_NAME AGND_PVPP_GHJ\g
J 0
(-5290 2635);
DISPLAY 0.659574 (-5290 2635);
PAINT MONO (-5290 2635);
DISPLAY INVISIBLE (-5290 2635);
FORCEPROP 1 LAST HDL_POWER AGND_PVPP_GHJ
J 1
(-5275 2500);
DISPLAY 0.617021 (-5275 2500);
PAINT GREEN (-5275 2500);
FORCEPROP 2 LAST CDS_LIB mstr_symbols
J 0
(-5300 2575);
PAINT MONO (-5300 2575);
DISPLAY INVISIBLE (-5300 2575);
FORCEPROP 1 LAST PATH I244
J 0
(-5225 2575);
DISPLAY 0.872340 (-5225 2575);
PAINT AQUA (-5225 2575);
DISPLAY INVISIBLE (-5225 2575);
FORCEPROP 2 LAST BOM_COST PVPP_KLM_VR
J 0
(-5450 2525);
DISPLAY 1.042553 (-5450 2525);
PAINT WHITE (-5450 2525);
DISPLAY INVISIBLE (-5450 2525);
FORCEPROP 2 LAST ROOM PVPP_KLM_VR
J 0
(-5450 2525);
DISPLAY 1.042553 (-5450 2525);
PAINT GREEN (-5450 2525);
DISPLAY INVISIBLE (-5450 2525);
FORCEPROP 1 LAST VOLTAGE 0.0V
J 0
(-5345 2532);
DISPLAY 0.340426 (-5345 2532);
PAINT SKYBLUE (-5345 2532);
DISPLAY INVISIBLE (-5345 2532);
FORCEPROP 1 LAST BODY_TYPE PLUMBING
J 0
(-5345 2532);
DISPLAY 0.340426 (-5345 2532);
PAINT GREEN (-5345 2532);
DISPLAY INVISIBLE (-5345 2532);
FORCEADD GND..1
(-1400 3175);
FORCEPROP 3 LASTPIN (-1400 3225) SIG_NAME GND\g
J 0
(-1390 3235);
DISPLAY 0.659574 (-1390 3235);
PAINT MONO (-1390 3235);
DISPLAY INVISIBLE (-1390 3235);
FORCEPROP 1 LAST HDL_POWER GND
J 0
(-1400 3325);
DISPLAY 0.872340 (-1400 3325);
PAINT GREEN (-1400 3325);
DISPLAY INVISIBLE (-1400 3325);
FORCEPROP 1 LAST BODY_TYPE PLUMBING
J 0
(-1445 3132);
DISPLAY 0.340426 (-1445 3132);
PAINT GREEN (-1445 3132);
DISPLAY INVISIBLE (-1445 3132);
FORCEPROP 2 LAST BOM_COST PVPP_KLM_VR
J 0
(-2250 3250);
DISPLAY 1.042553 (-2250 3250);
PAINT WHITE (-2250 3250);
DISPLAY INVISIBLE (-2250 3250);
FORCEPROP 2 LAST ROOM PVPP_KLM_VR
J 0
(-1975 3250);
DISPLAY 1.042553 (-1975 3250);
PAINT GREEN (-1975 3250);
DISPLAY INVISIBLE (-1975 3250);
FORCEPROP 1 LAST SIZE 1B
J 0
(-1325 3125);
DISPLAY 0.872340 (-1325 3125);
PAINT GREEN (-1325 3125);
DISPLAY INVISIBLE (-1325 3125);
FORCEPROP 1 LAST PATH I246
J 0
(-1325 3175);
DISPLAY 0.872340 (-1325 3175);
PAINT AQUA (-1325 3175);
DISPLAY INVISIBLE (-1325 3175);
FORCEPROP 2 LAST CDS_LIB mstr_symbols
J 0
(-1400 3175);
PAINT MONO (-1400 3175);
DISPLAY INVISIBLE (-1400 3175);
FORCEPROP 1 LAST VOLTAGE 0
J 0
(-1400 3175);
PAINT SKYBLUE (-1400 3175);
DISPLAY INVISIBLE (-1400 3175);
FORCEADD RES..1
(-3375 825);
FORCEPROP 1 LAST PACK_TYPE 0402
J 0
(-3125 675);
DISPLAY 0.617021 (-3125 675);
PAINT SKYBLUE (-3125 675);
FORCEPROP 1 LASTPIN (-3275 825) $PN 2
J 0
(-3313 837);
DISPLAY 0.617021 (-3313 837);
PAINT ORANGE (-3313 837);
FORCEPROP 1 LAST PART_NUMBER G21796-250
J 0
(-3425 925);
DISPLAY 0.617021 (-3425 925);
PAINT BLUE (-3425 925);
FORCEPROP 1 LAST TOLERANCE 1.0%
J 0
(-3375 725);
DISPLAY 0.617021 (-3375 725);
PAINT SKYBLUE (-3375 725);
FORCEPROP 1 LAST MATERIAL CHIP
J 0
(-3375 675);
DISPLAY 0.617021 (-3375 675);
PAINT SKYBLUE (-3375 675);
FORCEPROP 1 LASTPIN (-3475 825) $PN 1
J 0
(-3463 837);
DISPLAY 0.617021 (-3463 837);
PAINT ORANGE (-3463 837);
FORCEPROP 1 LAST WATTAGE 1/16W
J 2
(-3400 675);
DISPLAY 0.617021 (-3400 675);
PAINT SKYBLUE (-3400 675);
FORCEPROP 1 LAST VALUE 22.1
J 2
(-3400 725);
DISPLAY 0.617021 (-3400 725);
PAINT SKYBLUE (-3400 725);
FORCEPROP 1 LAST LOCATION R4G12
J 0
(-3425 875);
DISPLAY 0.617021 (-3425 875);
PAINT AQUA (-3425 875);
FORCEPROP 2 LAST SEC_TYPE 0402
J 0
(-3425 1025);
DISPLAY 1.021277 (-3425 1025);
PAINT ORANGE (-3425 1025);
DISPLAY INVISIBLE (-3425 1025);
FORCEPROP 2 LAST SEC 1
J 0
(-3425 1025);
DISPLAY 0.680851 (-3425 1025);
PAINT MONO (-3425 1025);
DISPLAY INVISIBLE (-3425 1025);
FORCEPROP 2 LAST ROOM PVPP_GHJ_VR
J 0
(-3425 925);
DISPLAY 1.361702 (-3425 925);
PAINT ORANGE (-3425 925);
DISPLAY INVISIBLE (-3425 925);
FORCEPROP 1 LAST PATH I247
J 0
(-3425 975);
DISPLAY 0.978723 (-3425 975);
PAINT WHITE (-3425 975);
DISPLAY INVISIBLE (-3425 975);
FORCEPROP 2 LAST CDS_LOCATION R4G12
J 0
(-3425 875);
DISPLAY 0.617021 (-3425 875);
PAINT AQUA (-3425 875);
DISPLAY INVISIBLE (-3425 875);
FORCEPROP 2 LAST CDS_LIB mstr_discrete
J 0
(-3375 825);
PAINT MONO (-3375 825);
DISPLAY INVISIBLE (-3375 825);
FORCEADD CAP..1
(-6600 4000);
FORCEPROP 1 LAST LOCATION C6U4
J 0
(-6550 4100);
DISPLAY 0.617021 (-6550 4100);
PAINT AQUA (-6550 4100);
FORCEPROP 1 LASTPIN (-6600 4100) $PN 1
J 0
(-6590 4080);
DISPLAY 0.617021 (-6590 4080);
PAINT ORANGE (-6590 4080);
FORCEPROP 1 LAST PACK_TYPE 0805
J 0
(-6550 3800);
DISPLAY 0.617021 (-6550 3800);
PAINT SKYBLUE (-6550 3800);
FORCEPROP 1 LAST VALUE 10UF
J 0
(-6550 4050);
DISPLAY 0.617021 (-6550 4050);
PAINT SKYBLUE (-6550 4050);
FORCEPROP 1 LASTPIN (-6600 3900) $PN 2
J 0
(-6590 3880);
DISPLAY 0.617021 (-6590 3880);
PAINT ORANGE (-6590 3880);
FORCEPROP 1 LAST PART_NUMBER C95333-007
J 0
(-6550 3850);
DISPLAY 0.617021 (-6550 3850);
PAINT BLUE (-6550 3850);
FORCEPROP 1 LAST MATERIAL X6S
J 0
(-6550 3900);
DISPLAY 0.617021 (-6550 3900);
PAINT SKYBLUE (-6550 3900);
FORCEPROP 1 LAST VOLTAGE 16V
J 0
(-6550 4000);
DISPLAY 0.617021 (-6550 4000);
PAINT SKYBLUE (-6550 4000);
FORCEPROP 1 LAST TOLERANCE 10%
J 0
(-6550 3950);
DISPLAY 0.617021 (-6550 3950);
PAINT SKYBLUE (-6550 3950);
FORCEPROP 2 LAST CDS_LIB mstr_discrete
J 0
(-6600 4000);
PAINT MONO (-6600 4000);
DISPLAY INVISIBLE (-6600 4000);
FORCEPROP 2 LAST CDS_LOCATION C6U4
J 0
(-6550 4100);
DISPLAY 0.617021 (-6550 4100);
PAINT AQUA (-6550 4100);
DISPLAY INVISIBLE (-6550 4100);
FORCEPROP 1 LAST PATH I248
J 0
(-6550 4150);
DISPLAY 0.978723 (-6550 4150);
PAINT WHITE (-6550 4150);
DISPLAY INVISIBLE (-6550 4150);
FORCEPROP 2 LAST SEC 1
J 0
(-6550 4200);
DISPLAY 0.680851 (-6550 4200);
PAINT MONO (-6550 4200);
DISPLAY INVISIBLE (-6550 4200);
FORCEPROP 2 LAST SEC_TYPE 0805
J 0
(-6550 4200);
DISPLAY 1.021277 (-6550 4200);
PAINT ORANGE (-6550 4200);
DISPLAY INVISIBLE (-6550 4200);
FORCEADD GND..1
(-6600 3800);
FORCEPROP 3 LASTPIN (-6600 3850) SIG_NAME GND\g
J 0
(-6590 3860);
DISPLAY 0.659574 (-6590 3860);
PAINT MONO (-6590 3860);
DISPLAY INVISIBLE (-6590 3860);
FORCEPROP 2 LAST ROOM PVPP_KLM_VR
J 0
(-7175 3875);
DISPLAY 1.042553 (-7175 3875);
PAINT GREEN (-7175 3875);
DISPLAY INVISIBLE (-7175 3875);
FORCEPROP 2 LAST BOM_COST PVPP_KLM_VR
J 0
(-7450 3875);
DISPLAY 1.042553 (-7450 3875);
PAINT WHITE (-7450 3875);
DISPLAY INVISIBLE (-7450 3875);
FORCEPROP 2 LAST CDS_LIB mstr_symbols
J 0
(-6600 3800);
PAINT MONO (-6600 3800);
DISPLAY INVISIBLE (-6600 3800);
FORCEPROP 1 LAST VOLTAGE 0
J 0
(-6600 3800);
PAINT SKYBLUE (-6600 3800);
DISPLAY INVISIBLE (-6600 3800);
FORCEPROP 1 LAST PATH I249
J 0
(-6525 3800);
DISPLAY 0.872340 (-6525 3800);
PAINT AQUA (-6525 3800);
DISPLAY INVISIBLE (-6525 3800);
FORCEPROP 1 LAST SIZE 1B
J 0
(-6525 3750);
DISPLAY 0.872340 (-6525 3750);
PAINT GREEN (-6525 3750);
DISPLAY INVISIBLE (-6525 3750);
FORCEPROP 1 LAST BODY_TYPE PLUMBING
J 0
(-6645 3757);
DISPLAY 0.340426 (-6645 3757);
PAINT GREEN (-6645 3757);
DISPLAY INVISIBLE (-6645 3757);
FORCEPROP 1 LAST HDL_POWER GND
J 0
(-6600 3950);
DISPLAY 0.872340 (-6600 3950);
PAINT GREEN (-6600 3950);
DISPLAY INVISIBLE (-6600 3950);
FORCEADD GND..1
(-6250 3800);
FORCEPROP 3 LASTPIN (-6250 3850) SIG_NAME GND\g
J 0
(-6240 3860);
DISPLAY 0.659574 (-6240 3860);
PAINT MONO (-6240 3860);
DISPLAY INVISIBLE (-6240 3860);
FORCEPROP 2 LAST BOM_COST PVPP_KLM_VR
J 0
(-7100 3875);
DISPLAY 1.042553 (-7100 3875);
PAINT WHITE (-7100 3875);
DISPLAY INVISIBLE (-7100 3875);
FORCEPROP 2 LAST ROOM PVPP_KLM_VR
J 0
(-6825 3875);
DISPLAY 1.042553 (-6825 3875);
PAINT GREEN (-6825 3875);
DISPLAY INVISIBLE (-6825 3875);
FORCEPROP 1 LAST PATH I250
J 0
(-6175 3800);
DISPLAY 0.872340 (-6175 3800);
PAINT AQUA (-6175 3800);
DISPLAY INVISIBLE (-6175 3800);
FORCEPROP 2 LAST CDS_LIB mstr_symbols
J 0
(-6250 3800);
PAINT MONO (-6250 3800);
DISPLAY INVISIBLE (-6250 3800);
FORCEPROP 1 LAST SIZE 1B
J 0
(-6175 3750);
DISPLAY 0.872340 (-6175 3750);
PAINT GREEN (-6175 3750);
DISPLAY INVISIBLE (-6175 3750);
FORCEPROP 1 LAST VOLTAGE 0
J 0
(-6250 3800);
PAINT SKYBLUE (-6250 3800);
DISPLAY INVISIBLE (-6250 3800);
FORCEPROP 1 LAST BODY_TYPE PLUMBING
J 0
(-6295 3757);
DISPLAY 0.340426 (-6295 3757);
PAINT GREEN (-6295 3757);
DISPLAY INVISIBLE (-6295 3757);
FORCEPROP 1 LAST HDL_POWER GND
J 0
(-6250 3950);
DISPLAY 0.872340 (-6250 3950);
PAINT GREEN (-6250 3950);
DISPLAY INVISIBLE (-6250 3950);
FORCEADD GND..1
(-5875 3800);
FORCEPROP 3 LASTPIN (-5875 3850) SIG_NAME GND\g
J 0
(-5865 3860);
DISPLAY 0.659574 (-5865 3860);
PAINT MONO (-5865 3860);
DISPLAY INVISIBLE (-5865 3860);
FORCEPROP 1 LAST VOLTAGE 0
J 0
(-5875 3800);
PAINT SKYBLUE (-5875 3800);
DISPLAY INVISIBLE (-5875 3800);
FORCEPROP 1 LAST SIZE 1B
J 0
(-5800 3750);
DISPLAY 0.872340 (-5800 3750);
PAINT GREEN (-5800 3750);
DISPLAY INVISIBLE (-5800 3750);
FORCEPROP 2 LAST CDS_LIB mstr_symbols
J 0
(-5875 3800);
PAINT MONO (-5875 3800);
DISPLAY INVISIBLE (-5875 3800);
FORCEPROP 1 LAST PATH I251
J 0
(-5800 3800);
DISPLAY 0.872340 (-5800 3800);
PAINT AQUA (-5800 3800);
DISPLAY INVISIBLE (-5800 3800);
FORCEPROP 2 LAST ROOM PVPP_KLM_VR
J 0
(-6450 3875);
DISPLAY 1.042553 (-6450 3875);
PAINT GREEN (-6450 3875);
DISPLAY INVISIBLE (-6450 3875);
FORCEPROP 2 LAST BOM_COST PVPP_KLM_VR
J 0
(-6725 3875);
DISPLAY 1.042553 (-6725 3875);
PAINT WHITE (-6725 3875);
DISPLAY INVISIBLE (-6725 3875);
FORCEPROP 1 LAST BODY_TYPE PLUMBING
J 0
(-5920 3757);
DISPLAY 0.340426 (-5920 3757);
PAINT GREEN (-5920 3757);
DISPLAY INVISIBLE (-5920 3757);
FORCEPROP 1 LAST HDL_POWER GND
J 0
(-5875 3950);
DISPLAY 0.872340 (-5875 3950);
PAINT GREEN (-5875 3950);
DISPLAY INVISIBLE (-5875 3950);
FORCEADD GND..1
(-5450 3800);
FORCEPROP 3 LASTPIN (-5450 3850) SIG_NAME GND\g
J 0
(-5440 3860);
DISPLAY 0.659574 (-5440 3860);
PAINT MONO (-5440 3860);
DISPLAY INVISIBLE (-5440 3860);
FORCEPROP 1 LAST SIZE 1B
J 0
(-5375 3750);
DISPLAY 0.872340 (-5375 3750);
PAINT GREEN (-5375 3750);
DISPLAY INVISIBLE (-5375 3750);
FORCEPROP 1 LAST PATH I252
J 0
(-5375 3800);
DISPLAY 0.872340 (-5375 3800);
PAINT AQUA (-5375 3800);
DISPLAY INVISIBLE (-5375 3800);
FORCEPROP 1 LAST VOLTAGE 0
J 0
(-5450 3800);
PAINT SKYBLUE (-5450 3800);
DISPLAY INVISIBLE (-5450 3800);
FORCEPROP 2 LAST CDS_LIB mstr_symbols
J 0
(-5450 3800);
PAINT MONO (-5450 3800);
DISPLAY INVISIBLE (-5450 3800);
FORCEPROP 2 LAST ROOM PVPP_KLM_VR
J 0
(-6025 3875);
DISPLAY 1.042553 (-6025 3875);
PAINT GREEN (-6025 3875);
DISPLAY INVISIBLE (-6025 3875);
FORCEPROP 2 LAST BOM_COST PVPP_KLM_VR
J 0
(-6300 3875);
DISPLAY 1.042553 (-6300 3875);
PAINT WHITE (-6300 3875);
DISPLAY INVISIBLE (-6300 3875);
FORCEPROP 1 LAST BODY_TYPE PLUMBING
J 0
(-5495 3757);
DISPLAY 0.340426 (-5495 3757);
PAINT GREEN (-5495 3757);
DISPLAY INVISIBLE (-5495 3757);
FORCEPROP 1 LAST HDL_POWER GND
J 0
(-5450 3950);
DISPLAY 0.872340 (-5450 3950);
PAINT GREEN (-5450 3950);
DISPLAY INVISIBLE (-5450 3950);
FORCEADD CAP..1
(-6250 4000);
FORCEPROP 1 LAST LOCATION C4G2
J 0
(-6200 4100);
DISPLAY 0.617021 (-6200 4100);
PAINT AQUA (-6200 4100);
FORCEPROP 1 LASTPIN (-6250 4100) $PN 1
J 0
(-6240 4080);
DISPLAY 0.617021 (-6240 4080);
PAINT ORANGE (-6240 4080);
FORCEPROP 1 LAST VALUE 10UF
J 0
(-6200 4050);
DISPLAY 0.617021 (-6200 4050);
PAINT SKYBLUE (-6200 4050);
FORCEPROP 1 LAST PACK_TYPE 0805
J 0
(-6200 3800);
DISPLAY 0.617021 (-6200 3800);
PAINT SKYBLUE (-6200 3800);
FORCEPROP 1 LAST MATERIAL X6S
J 0
(-6200 3900);
DISPLAY 0.617021 (-6200 3900);
PAINT SKYBLUE (-6200 3900);
FORCEPROP 1 LAST VOLTAGE 16V
J 0
(-6200 4000);
DISPLAY 0.617021 (-6200 4000);
PAINT SKYBLUE (-6200 4000);
FORCEPROP 1 LAST TOLERANCE 10%
J 0
(-6200 3950);
DISPLAY 0.617021 (-6200 3950);
PAINT SKYBLUE (-6200 3950);
FORCEPROP 1 LASTPIN (-6250 3900) $PN 2
J 0
(-6240 3880);
DISPLAY 0.617021 (-6240 3880);
PAINT ORANGE (-6240 3880);
FORCEPROP 1 LAST PART_NUMBER C95333-007
J 0
(-6200 3850);
DISPLAY 0.617021 (-6200 3850);
PAINT BLUE (-6200 3850);
FORCEPROP 2 LAST SEC_TYPE 0805
J 0
(-6200 4200);
DISPLAY 1.021277 (-6200 4200);
PAINT ORANGE (-6200 4200);
DISPLAY INVISIBLE (-6200 4200);
FORCEPROP 2 LAST SEC 1
J 0
(-6200 4200);
DISPLAY 0.680851 (-6200 4200);
PAINT MONO (-6200 4200);
DISPLAY INVISIBLE (-6200 4200);
FORCEPROP 1 LAST PATH I253
J 0
(-6200 4150);
DISPLAY 0.978723 (-6200 4150);
PAINT WHITE (-6200 4150);
DISPLAY INVISIBLE (-6200 4150);
FORCEPROP 2 LAST CDS_LOCATION C4G2
J 0
(-6200 4100);
DISPLAY 0.617021 (-6200 4100);
PAINT AQUA (-6200 4100);
DISPLAY INVISIBLE (-6200 4100);
FORCEPROP 2 LAST CDS_LIB mstr_discrete
J 0
(-6250 4000);
PAINT MONO (-6250 4000);
DISPLAY INVISIBLE (-6250 4000);
FORCEADD CAP..1
(-5875 4000);
FORCEPROP 1 LASTPIN (-5875 3900) $PN 2
J 0
(-5865 3880);
DISPLAY 0.617021 (-5865 3880);
PAINT ORANGE (-5865 3880);
FORCEPROP 1 LAST MATERIAL X6S
J 0
(-5825 3900);
DISPLAY 0.617021 (-5825 3900);
PAINT SKYBLUE (-5825 3900);
FORCEPROP 1 LAST TOLERANCE 10%
J 0
(-5825 3950);
DISPLAY 0.617021 (-5825 3950);
PAINT SKYBLUE (-5825 3950);
FORCEPROP 1 LAST VOLTAGE 16V
J 0
(-5825 4000);
DISPLAY 0.617021 (-5825 4000);
PAINT SKYBLUE (-5825 4000);
FORCEPROP 1 LAST VALUE 10UF
J 0
(-5825 4050);
DISPLAY 0.617021 (-5825 4050);
PAINT SKYBLUE (-5825 4050);
FORCEPROP 1 LAST LOCATION C6U7
J 0
(-5825 4100);
DISPLAY 0.617021 (-5825 4100);
PAINT AQUA (-5825 4100);
FORCEPROP 1 LAST PART_NUMBER C95333-007
J 0
(-5825 3850);
DISPLAY 0.617021 (-5825 3850);
PAINT BLUE (-5825 3850);
FORCEPROP 1 LAST PACK_TYPE 0805
J 0
(-5825 3800);
DISPLAY 0.617021 (-5825 3800);
PAINT SKYBLUE (-5825 3800);
FORCEPROP 1 LASTPIN (-5875 4100) $PN 1
J 0
(-5865 4080);
DISPLAY 0.617021 (-5865 4080);
PAINT ORANGE (-5865 4080);
FORCEPROP 2 LAST SEC_TYPE 0805
J 0
(-5825 4200);
DISPLAY 1.021277 (-5825 4200);
PAINT ORANGE (-5825 4200);
DISPLAY INVISIBLE (-5825 4200);
FORCEPROP 2 LAST SEC 1
J 0
(-5825 4200);
DISPLAY 0.680851 (-5825 4200);
PAINT MONO (-5825 4200);
DISPLAY INVISIBLE (-5825 4200);
FORCEPROP 1 LAST PATH I254
J 0
(-5825 4150);
DISPLAY 0.978723 (-5825 4150);
PAINT WHITE (-5825 4150);
DISPLAY INVISIBLE (-5825 4150);
FORCEPROP 2 LAST CDS_LOCATION C6U7
J 0
(-5825 4100);
DISPLAY 0.617021 (-5825 4100);
PAINT AQUA (-5825 4100);
DISPLAY INVISIBLE (-5825 4100);
FORCEPROP 2 LAST CDS_LIB mstr_discrete
J 0
(-5875 4000);
PAINT MONO (-5875 4000);
DISPLAY INVISIBLE (-5875 4000);
FORCEADD CAP..1
(-5450 4000);
FORCEPROP 1 LAST LOCATION C6U8
J 0
(-5400 4100);
DISPLAY 0.617021 (-5400 4100);
PAINT AQUA (-5400 4100);
FORCEPROP 1 LAST VALUE 10UF
J 0
(-5400 4050);
DISPLAY 0.617021 (-5400 4050);
PAINT SKYBLUE (-5400 4050);
FORCEPROP 1 LAST VOLTAGE 16V
J 0
(-5400 4000);
DISPLAY 0.617021 (-5400 4000);
PAINT SKYBLUE (-5400 4000);
FORCEPROP 1 LASTPIN (-5450 4100) $PN 1
J 0
(-5440 4080);
DISPLAY 0.617021 (-5440 4080);
PAINT ORANGE (-5440 4080);
FORCEPROP 1 LASTPIN (-5450 3900) $PN 2
J 0
(-5440 3880);
DISPLAY 0.617021 (-5440 3880);
PAINT ORANGE (-5440 3880);
FORCEPROP 1 LAST TOLERANCE 10%
J 0
(-5400 3950);
DISPLAY 0.617021 (-5400 3950);
PAINT SKYBLUE (-5400 3950);
FORCEPROP 1 LAST MATERIAL X6S
J 0
(-5400 3900);
DISPLAY 0.617021 (-5400 3900);
PAINT SKYBLUE (-5400 3900);
FORCEPROP 1 LAST PACK_TYPE 0805
J 0
(-5400 3800);
DISPLAY 0.617021 (-5400 3800);
PAINT SKYBLUE (-5400 3800);
FORCEPROP 1 LAST PART_NUMBER C95333-007
J 0
(-5400 3850);
DISPLAY 0.617021 (-5400 3850);
PAINT BLUE (-5400 3850);
FORCEPROP 2 LAST SEC_TYPE 0805
J 0
(-5400 4200);
DISPLAY 1.021277 (-5400 4200);
PAINT ORANGE (-5400 4200);
DISPLAY INVISIBLE (-5400 4200);
FORCEPROP 2 LAST SEC 1
J 0
(-5400 4200);
DISPLAY 0.680851 (-5400 4200);
PAINT MONO (-5400 4200);
DISPLAY INVISIBLE (-5400 4200);
FORCEPROP 1 LAST PATH I255
J 0
(-5400 4150);
DISPLAY 0.978723 (-5400 4150);
PAINT WHITE (-5400 4150);
DISPLAY INVISIBLE (-5400 4150);
FORCEPROP 2 LAST CDS_LOCATION C6U8
J 0
(-5400 4100);
DISPLAY 0.617021 (-5400 4100);
PAINT AQUA (-5400 4100);
DISPLAY INVISIBLE (-5400 4100);
FORCEPROP 2 LAST CDS_LIB mstr_discrete
J 0
(-5450 4000);
PAINT MONO (-5450 4000);
DISPLAY INVISIBLE (-5450 4000);
FORCEADD CAPP..1
(-1400 3500);
FORCEPROP 1 LASTPIN (-1400 3600) $PN 1
J 0
(-1390 3585);
DISPLAY 0.617021 (-1390 3585);
PAINT ORANGE (-1390 3585);
FORCEPROP 1 LASTPIN (-1400 3400) $PN 2
J 0
(-1390 3385);
DISPLAY 0.617021 (-1390 3385);
PAINT ORANGE (-1390 3385);
FORCEPROP 1 LAST PART_NUMBER 724613-067
J 0
(-1350 3350);
DISPLAY 0.617021 (-1350 3350);
PAINT BLUE (-1350 3350);
FORCEPROP 1 LAST PACK_TYPE 7343
J 0
(-1350 3400);
DISPLAY 0.617021 (-1350 3400);
PAINT SKYBLUE (-1350 3400);
FORCEPROP 1 LAST MATERIAL POSCAP
J 0
(-1350 3450);
DISPLAY 0.617021 (-1350 3450);
PAINT SKYBLUE (-1350 3450);
FORCEPROP 1 LAST VOLTAGE 4V
J 0
(-1350 3500);
DISPLAY 0.617021 (-1350 3500);
PAINT SKYBLUE (-1350 3500);
FORCEPROP 1 LAST TOLERANCE 20%
J 0
(-1350 3550);
DISPLAY 0.617021 (-1350 3550);
PAINT SKYBLUE (-1350 3550);
FORCEPROP 1 LAST VALUE 220UF
J 0
(-1350 3600);
DISPLAY 0.617021 (-1350 3600);
PAINT SKYBLUE (-1350 3600);
FORCEPROP 1 LAST LOCATION C4F11
J 0
(-1350 3650);
DISPLAY 0.617021 (-1350 3650);
PAINT AQUA (-1350 3650);
FORCEPROP 0 LAST GROUP PWR_BULK_CAP
J 0
(-1335 3251);
DISPLAY 0.638298 (-1335 3251);
PAINT BROWN (-1335 3251);
DISPLAY BOTH (-1335 3251);
FORCEPROP 1 LAST PATH I256
J 0
(-1350 3650);
DISPLAY 0.978723 (-1350 3650);
PAINT ORANGE (-1350 3650);
DISPLAY INVISIBLE (-1350 3650);
FORCEPROP 2 LAST CDS_LOCATION C4F11
J 0
(-1350 3600);
DISPLAY 0.617021 (-1350 3600);
PAINT AQUA (-1350 3600);
DISPLAY INVISIBLE (-1350 3600);
FORCEPROP 2 LAST SEC 1
J 0
(-1350 3700);
DISPLAY 0.680851 (-1350 3700);
PAINT MONO (-1350 3700);
DISPLAY INVISIBLE (-1350 3700);
FORCEPROP 2 LAST SEC_TYPE 7343
J 0
(-1350 3700);
DISPLAY 1.021277 (-1350 3700);
PAINT ORANGE (-1350 3700);
DISPLAY INVISIBLE (-1350 3700);
FORCEPROP 2 LAST CDS_LIB mstr_discrete
J 0
(-1400 3500);
PAINT ORANGE (-1400 3500);
DISPLAY INVISIBLE (-1400 3500);
FORCEADD RES..2
(-950 2475);
FORCEPROP 1 LASTPIN (-950 2375) $PN 2
J 0
(-945 2385);
DISPLAY 0.617021 (-945 2385);
PAINT ORANGE (-945 2385);
FORCEPROP 1 LASTPIN (-950 2575) $PN 1
J 0
(-945 2537);
DISPLAY 0.617021 (-945 2537);
PAINT ORANGE (-945 2537);
FORCEPROP 1 LAST LOCATION R4G10
J 0
(-905 2600);
DISPLAY 0.617021 (-905 2600);
PAINT AQUA (-905 2600);
FORCEPROP 1 LAST VALUE 1.0K
J 0
(-905 2550);
DISPLAY 0.617021 (-905 2550);
PAINT SKYBLUE (-905 2550);
FORCEPROP 1 LAST TOLERANCE 0.1%
J 0
(-905 2500);
DISPLAY 0.617021 (-905 2500);
PAINT SKYBLUE (-905 2500);
FORCEPROP 1 LAST WATTAGE 1/16W
J 0
(-910 2450);
DISPLAY 0.617021 (-910 2450);
PAINT SKYBLUE (-910 2450);
FORCEPROP 1 LAST PACK_TYPE 0402
J 0
(-910 2400);
DISPLAY 0.617021 (-910 2400);
PAINT SKYBLUE (-910 2400);
FORCEPROP 1 LAST MATERIAL CHIP
J 0
(-910 2350);
DISPLAY 0.617021 (-910 2350);
PAINT SKYBLUE (-910 2350);
FORCEPROP 1 LAST PART_NUMBER G85996-004
J 0
(-935 2300);
DISPLAY 0.617021 (-935 2300);
PAINT BLUE (-935 2300);
FORCEPROP 2 LAST ROOM PVPP_KLM_VR
J 0
(-905 2630);
PAINT GREEN (-905 2630);
DISPLAY INVISIBLE (-905 2630);
FORCEPROP 1 LAST PATH I266
J 0
(-900 2650);
DISPLAY 0.978723 (-900 2650);
PAINT WHITE (-900 2650);
DISPLAY INVISIBLE (-900 2650);
FORCEPROP 2 LAST CDS_LOCATION R4G10
J 0
(-905 2600);
DISPLAY 0.617021 (-905 2600);
PAINT AQUA (-905 2600);
DISPLAY INVISIBLE (-905 2600);
FORCEPROP 2 LAST SEC 1
J 0
(-900 2700);
DISPLAY 0.680851 (-900 2700);
PAINT MONO (-900 2700);
DISPLAY INVISIBLE (-900 2700);
FORCEPROP 2 LAST BOM_COST PVPP_KLM_VR
J 0
(-905 2655);
DISPLAY 1.042553 (-905 2655);
PAINT WHITE (-905 2655);
DISPLAY INVISIBLE (-905 2655);
FORCEPROP 2 LAST REUSE_ID 9
J 0
(-900 2700);
DISPLAY 1.042553 (-900 2700);
PAINT ORANGE (-900 2700);
DISPLAY INVISIBLE (-900 2700);
FORCEPROP 2 LAST SEC_TYPE 0402
J 0
(-900 2700);
DISPLAY 1.021277 (-900 2700);
PAINT ORANGE (-900 2700);
DISPLAY INVISIBLE (-900 2700);
FORCEPROP 0 LAST SPOF TRUE
J 0
(-900 2700);
DISPLAY 1.021277 (-900 2700);
PAINT ORANGE (-900 2700);
DISPLAY INVISIBLE (-900 2700);
FORCEPROP 2 LAST CDS_LIB mstr_discrete
J 0
(-950 2475);
PAINT MONO (-950 2475);
DISPLAY INVISIBLE (-950 2475);
FORCEADD CAP..1
(-950 1700);
FORCEPROP 1 LAST PART_NUMBER A36096-075
J 0
(-900 1550);
DISPLAY 0.617021 (-900 1550);
PAINT BLUE (-900 1550);
FORCEPROP 1 LAST PACK_TYPE 0402LF
J 0
(-900 1500);
DISPLAY 0.617021 (-900 1500);
PAINT SKYBLUE (-900 1500);
FORCEPROP 1 LAST LOCATION C4G11
J 0
(-900 1800);
DISPLAY 0.617021 (-900 1800);
PAINT AQUA (-900 1800);
FORCEPROP 1 LAST VALUE 2200PF
J 0
(-900 1750);
DISPLAY 0.617021 (-900 1750);
PAINT SKYBLUE (-900 1750);
FORCEPROP 1 LAST TOLERANCE 10%
J 0
(-900 1650);
DISPLAY 0.617021 (-900 1650);
PAINT SKYBLUE (-900 1650);
FORCEPROP 1 LASTPIN (-950 1800) $PN 1
J 0
(-940 1780);
DISPLAY 0.617021 (-940 1780);
PAINT ORANGE (-940 1780);
FORCEPROP 1 LASTPIN (-950 1600) $PN 2
J 0
(-940 1580);
DISPLAY 0.617021 (-940 1580);
PAINT ORANGE (-940 1580);
FORCEPROP 1 LAST MATERIAL X7R
J 0
(-900 1600);
DISPLAY 0.617021 (-900 1600);
PAINT SKYBLUE (-900 1600);
FORCEPROP 1 LAST VOLTAGE 50V
J 0
(-900 1700);
DISPLAY 0.617021 (-900 1700);
PAINT SKYBLUE (-900 1700);
FORCEPROP 2 LAST CDS_LIB mstr_discrete
J 0
(-950 1700);
PAINT ORANGE (-950 1700);
DISPLAY INVISIBLE (-950 1700);
FORCEPROP 2 LAST CDS_LOCATION C4G11
J 0
(-900 1800);
DISPLAY 0.617021 (-900 1800);
PAINT AQUA (-900 1800);
DISPLAY INVISIBLE (-900 1800);
FORCEPROP 2 LAST ROOM PVPP_KLM_VR
J 0
(-900 1825);
PAINT GREEN (-900 1825);
DISPLAY INVISIBLE (-900 1825);
FORCEPROP 2 LAST BOM_COST PVPP_KLM_VR
J 0
(-900 1850);
DISPLAY 1.042553 (-900 1850);
PAINT WHITE (-900 1850);
DISPLAY INVISIBLE (-900 1850);
FORCEPROP 2 LAST SEC 1
J 0
(-900 1900);
DISPLAY 0.680851 (-900 1900);
PAINT MONO (-900 1900);
DISPLAY INVISIBLE (-900 1900);
FORCEPROP 2 LAST SEC_TYPE 0402LF
J 0
(-900 1900);
DISPLAY 1.021277 (-900 1900);
PAINT ORANGE (-900 1900);
DISPLAY INVISIBLE (-900 1900);
FORCEPROP 0 LAST SPOF TRUE
J 0
(-900 1900);
DISPLAY 1.021277 (-900 1900);
PAINT ORANGE (-900 1900);
DISPLAY INVISIBLE (-900 1900);
FORCEPROP 1 LAST PATH I267
J 0
(-900 1850);
DISPLAY 0.978723 (-900 1850);
PAINT WHITE (-900 1850);
DISPLAY INVISIBLE (-900 1850);
FORCEPROP 2 LAST REUSE_ID 26
J 0
(-900 1900);
DISPLAY 1.042553 (-900 1900);
PAINT ORANGE (-900 1900);
DISPLAY INVISIBLE (-900 1900);
FORCEADD RES..2
(-1275 1800);
FORCEPROP 1 LAST TOLERANCE 1%
J 0
(-1230 1825);
DISPLAY 0.617021 (-1230 1825);
PAINT SKYBLUE (-1230 1825);
FORCEPROP 1 LAST WATTAGE 1/16W
J 0
(-1235 1775);
DISPLAY 0.617021 (-1235 1775);
PAINT SKYBLUE (-1235 1775);
FORCEPROP 1 LASTPIN (-1275 1700) $PN 2
J 0
(-1270 1710);
DISPLAY 0.617021 (-1270 1710);
PAINT WHITE (-1270 1710);
FORCEPROP 1 LAST LOCATION R4G7
J 0
(-1230 1925);
DISPLAY 0.617021 (-1230 1925);
PAINT AQUA (-1230 1925);
FORCEPROP 1 LAST VALUE 20.0K
J 0
(-1230 1875);
DISPLAY 0.617021 (-1230 1875);
PAINT SKYBLUE (-1230 1875);
FORCEPROP 1 LASTPIN (-1275 1900) $PN 1
J 0
(-1270 1862);
DISPLAY 0.617021 (-1270 1862);
PAINT WHITE (-1270 1862);
FORCEPROP 1 LAST PACK_TYPE 0402
J 0
(-1235 1725);
DISPLAY 0.617021 (-1235 1725);
PAINT SKYBLUE (-1235 1725);
FORCEPROP 1 LAST MATERIAL CHIP
J 0
(-1235 1675);
DISPLAY 0.617021 (-1235 1675);
PAINT SKYBLUE (-1235 1675);
FORCEPROP 1 LAST PART_NUMBER G21796-040
J 0
(-1260 1625);
DISPLAY 0.617021 (-1260 1625);
PAINT BLUE (-1260 1625);
FORCEPROP 2 LAST CDS_LIB mstr_discrete
J 0
(-1275 1800);
PAINT MONO (-1275 1800);
DISPLAY INVISIBLE (-1275 1800);
FORCEPROP 2 LAST BOM_COST PVPP_KLM_VR
J 0
(-1230 1980);
DISPLAY 1.042553 (-1230 1980);
PAINT WHITE (-1230 1980);
DISPLAY INVISIBLE (-1230 1980);
FORCEPROP 2 LAST REUSE_ID 9
J 0
(-1225 2025);
DISPLAY 1.042553 (-1225 2025);
PAINT ORANGE (-1225 2025);
DISPLAY INVISIBLE (-1225 2025);
FORCEPROP 0 LAST SPOF TRUE
J 0
(-1225 2025);
DISPLAY 1.021277 (-1225 2025);
PAINT ORANGE (-1225 2025);
DISPLAY INVISIBLE (-1225 2025);
FORCEPROP 2 LAST CDS_SEC 1
J 0
(-1225 2025);
DISPLAY 1.042553 (-1225 2025);
PAINT ORANGE (-1225 2025);
DISPLAY INVISIBLE (-1225 2025);
FORCEPROP 2 LAST $SEC 1
J 0
(-1225 2025);
DISPLAY 0.680851 (-1225 2025);
PAINT MONO (-1225 2025);
DISPLAY INVISIBLE (-1225 2025);
FORCEPROP 2 LAST CDS_LOCATION R4G7
J 0
(-1230 1925);
DISPLAY 0.617021 (-1230 1925);
PAINT AQUA (-1230 1925);
DISPLAY INVISIBLE (-1230 1925);
FORCEPROP 1 LAST PATH I270
J 0
(-1225 1975);
DISPLAY 0.978723 (-1225 1975);
PAINT WHITE (-1225 1975);
DISPLAY INVISIBLE (-1225 1975);
FORCEPROP 2 LAST ROOM PVPP_KLM_VR
J 0
(-1230 1955);
PAINT GREEN (-1230 1955);
DISPLAY INVISIBLE (-1230 1955);
FORCEADD RES..1
R 5
(-1275 2900);
FORCEPROP 1 LAST VALUE 0.0
J 0
(-1225 2950);
DISPLAY 0.617021 (-1225 2950);
PAINT SKYBLUE (-1225 2950);
FORCEPROP 1 LASTPIN (-1275 3000) $PN 1
J 0
(-1263 2988);
DISPLAY 0.617021 (-1263 2988);
PAINT ORANGE (-1263 2988);
FORCEPROP 1 LASTPIN (-1275 2800) $PN 2
J 0
(-1263 2838);
DISPLAY 0.617021 (-1263 2838);
PAINT ORANGE (-1263 2838);
FORCEPROP 1 LAST LOCATION R4G8
J 0
(-1100 2850);
DISPLAY 0.617021 (-1100 2850);
PAINT AQUA (-1100 2850);
FORCEPROP 1 LAST WATTAGE 1/16W
J 0
(-1225 2900);
DISPLAY 0.617021 (-1225 2900);
PAINT SKYBLUE (-1225 2900);
FORCEPROP 1 LAST TOLERANCE 5%
J 0
(-1200 2850);
DISPLAY 0.617021 (-1200 2850);
PAINT SKYBLUE (-1200 2850);
FORCEPROP 1 LAST MATERIAL CHIP
J 0
(-1250 2800);
DISPLAY 0.617021 (-1250 2800);
PAINT SKYBLUE (-1250 2800);
FORCEPROP 1 LAST PACK_TYPE 0402
J 0
(-1250 2750);
DISPLAY 0.617021 (-1250 2750);
PAINT SKYBLUE (-1250 2750);
FORCEPROP 1 LAST PART_NUMBER G21497-005
J 0
(-1250 2700);
DISPLAY 0.617021 (-1250 2700);
PAINT BLUE (-1250 2700);
FORCEPROP 2 LAST CDS_LOCATION R4G8
J 0
(-1175 2850);
DISPLAY 0.617021 (-1175 2850);
PAINT AQUA (-1175 2850);
DISPLAY INVISIBLE (-1175 2850);
FORCEPROP 2 LAST CDS_LIB mstr_discrete
J 0
(-1275 2900);
PAINT ORANGE (-1275 2900);
DISPLAY INVISIBLE (-1275 2900);
FORCEPROP 2 LAST SEC_TYPE 0402
J 0
(-1200 3050);
DISPLAY 1.021277 (-1200 3050);
PAINT ORANGE (-1200 3050);
DISPLAY INVISIBLE (-1200 3050);
FORCEPROP 0 LAST SPOF TRUE
J 0
(-1225 3050);
DISPLAY 1.021277 (-1225 3050);
PAINT ORANGE (-1225 3050);
DISPLAY INVISIBLE (-1225 3050);
FORCEPROP 2 LAST ROOM PVPP_KLM_VR
R 3
J 0
(-1125 2950);
DISPLAY 1.659574 (-1125 2950);
PAINT GREEN (-1125 2950);
DISPLAY INVISIBLE (-1125 2950);
FORCEPROP 1 LAST PATH I271
R 3
J 0
(-1125 2950);
DISPLAY 0.978723 (-1125 2950);
PAINT WHITE (-1125 2950);
DISPLAY INVISIBLE (-1125 2950);
FORCEPROP 2 LAST SEC 1
J 0
(-1200 3050);
DISPLAY 0.680851 (-1200 3050);
PAINT MONO (-1200 3050);
DISPLAY INVISIBLE (-1200 3050);
FORCEADD RES..1
(-2000 2300);
FORCEPROP 1 LASTPIN (-2100 2300) $PN 1
J 0
(-2088 2312);
DISPLAY 0.617021 (-2088 2312);
PAINT ORANGE (-2088 2312);
FORCEPROP 1 LASTPIN (-1900 2300) $PN 2
J 0
(-1938 2312);
DISPLAY 0.617021 (-1938 2312);
PAINT ORANGE (-1938 2312);
FORCEPROP 1 LAST LOCATION R4G13
J 0
(-2050 2350);
DISPLAY 0.617021 (-2050 2350);
PAINT AQUA (-2050 2350);
FORCEPROP 1 LAST PACK_TYPE 0402
J 0
(-1950 2175);
DISPLAY 0.617021 (-1950 2175);
PAINT SKYBLUE (-1950 2175);
FORCEPROP 1 LAST MATERIAL CHIP
J 0
(-2000 2125);
DISPLAY 0.617021 (-2000 2125);
PAINT SKYBLUE (-2000 2125);
FORCEPROP 1 LAST PART_NUMBER G21796-242
J 0
(-2150 2225);
DISPLAY 0.617021 (-2150 2225);
PAINT BLUE (-2150 2225);
FORCEPROP 1 LAST TOLERANCE 1.0%
J 0
(-2050 2175);
DISPLAY 0.617021 (-2050 2175);
PAINT SKYBLUE (-2050 2175);
FORCEPROP 1 LAST WATTAGE 1/16W
J 2
(-2025 2125);
DISPLAY 0.617021 (-2025 2125);
PAINT SKYBLUE (-2025 2125);
FORCEPROP 1 LAST VALUE 7.87K
J 2
(-2100 2175);
DISPLAY 0.617021 (-2100 2175);
PAINT SKYBLUE (-2100 2175);
FORCEPROP 2 LAST ROOM PVPP_KLM_VR
J 0
(-2000 2300);
PAINT GREEN (-2000 2300);
DISPLAY INVISIBLE (-2000 2300);
FORCEPROP 2 LAST CDS_LIB mstr_discrete
J 0
(-2000 2300);
PAINT MONO (-2000 2300);
DISPLAY INVISIBLE (-2000 2300);
FORCEPROP 2 LAST BOM_COST PVPP_KLM_VR
J 0
(-2000 2300);
PAINT WHITE (-2000 2300);
DISPLAY INVISIBLE (-2000 2300);
FORCEPROP 0 LAST SEC 1
J 0
(-2050 2400);
PAINT MONO (-2050 2400);
DISPLAY INVISIBLE (-2050 2400);
FORCEPROP 1 LAST PATH I272
J 0
(-2050 2450);
DISPLAY 0.978723 (-2050 2450);
PAINT WHITE (-2050 2450);
DISPLAY INVISIBLE (-2050 2450);
FORCEPROP 2 LAST CDS_LOCATION R4G13
J 0
(-2050 2350);
DISPLAY 0.617021 (-2050 2350);
PAINT AQUA (-2050 2350);
DISPLAY INVISIBLE (-2050 2350);
FORCEPROP 2 LAST REUSE_ID 13
J 0
(-2050 2500);
DISPLAY 1.042553 (-2050 2500);
PAINT ORANGE (-2050 2500);
DISPLAY INVISIBLE (-2050 2500);
FORCEPROP 2 LAST SEC_TYPE 0402
J 0
(-2050 2500);
DISPLAY 1.021277 (-2050 2500);
PAINT ORANGE (-2050 2500);
DISPLAY INVISIBLE (-2050 2500);
FORCEADD CAP..2
R 2
(-2150 2675);
FORCEPROP 1 LASTPIN (-2250 2675) $PN 2
J 2
(-2235 2690);
DISPLAY 0.617021 (-2235 2690);
PAINT ORANGE (-2235 2690);
FORCEPROP 1 LASTPIN (-2050 2675) $PN 1
J 2
(-2040 2690);
DISPLAY 0.617021 (-2040 2690);
PAINT ORANGE (-2040 2690);
FORCEPROP 1 LAST LOCATION C4G6
J 1
(-2150 2725);
DISPLAY 0.617021 (-2150 2725);
PAINT AQUA (-2150 2725);
FORCEPROP 1 LAST VOLTAGE 50V
J 2
(-2200 2575);
DISPLAY 0.617021 (-2200 2575);
PAINT SKYBLUE (-2200 2575);
FORCEPROP 1 LAST TOLERANCE 5%
J 0
(-2075 2525);
DISPLAY 0.617021 (-2075 2525);
PAINT SKYBLUE (-2075 2525);
FORCEPROP 1 LAST MATERIAL COG
J 2
(-1950 2575);
DISPLAY 0.617021 (-1950 2575);
PAINT SKYBLUE (-1950 2575);
FORCEPROP 1 LAST VALUE 100.0PF
J 0
(-2200 2575);
DISPLAY 0.617021 (-2200 2575);
PAINT SKYBLUE (-2200 2575);
FORCEPROP 1 LAST PART_NUMBER A36095-026
J 1
(-2150 2475);
DISPLAY 0.617021 (-2150 2475);
PAINT BLUE (-2150 2475);
FORCEPROP 1 LAST PACK_TYPE 0402LF
J 1
(-2175 2525);
DISPLAY 0.617021 (-2175 2525);
PAINT SKYBLUE (-2175 2525);
FORCEPROP 2 LAST SEC_TYPE 0402LF
J 0
(-2150 2925);
DISPLAY 1.021277 (-2150 2925);
PAINT ORANGE (-2150 2925);
DISPLAY INVISIBLE (-2150 2925);
FORCEPROP 2 LAST REUSE_ID 27
J 0
(-2150 2925);
DISPLAY 1.042553 (-2150 2925);
PAINT ORANGE (-2150 2925);
DISPLAY INVISIBLE (-2150 2925);
FORCEPROP 2 LAST BOM_COST PVPP_KLM_VR
J 0
(-2195 2835);
DISPLAY 1.042553 (-2195 2835);
PAINT WHITE (-2195 2835);
DISPLAY INVISIBLE (-2195 2835);
FORCEPROP 2 LAST SEC 1
J 0
(-2150 2925);
DISPLAY 0.680851 (-2150 2925);
PAINT MONO (-2150 2925);
DISPLAY INVISIBLE (-2150 2925);
FORCEPROP 1 LAST PATH I273
J 2
(-2150 2875);
DISPLAY 0.978723 (-2150 2875);
PAINT WHITE (-2150 2875);
DISPLAY INVISIBLE (-2150 2875);
FORCEPROP 2 LAST ROOM PVPP_KLM_VR
J 2
(-2150 2800);
DISPLAY 0.765957 (-2150 2800);
PAINT GREEN (-2150 2800);
DISPLAY INVISIBLE (-2150 2800);
FORCEPROP 2 LAST CDS_LOCATION C4G6
J 1
(-2150 2725);
DISPLAY 0.617021 (-2150 2725);
PAINT AQUA (-2150 2725);
DISPLAY INVISIBLE (-2150 2725);
FORCEPROP 2 LAST CDS_LIB mstr_discrete
J 0
(-2150 2675);
PAINT ORANGE (-2150 2675);
DISPLAY INVISIBLE (-2150 2675);
FORCEADD CAP..2
R 2
(-2775 2300);
FORCEPROP 1 LAST TOLERANCE 10%
J 0
(-2750 2125);
DISPLAY 0.617021 (-2750 2125);
PAINT SKYBLUE (-2750 2125);
FORCEPROP 1 LAST LOCATION C4G10
J 1
(-2775 2375);
DISPLAY 0.617021 (-2775 2375);
PAINT AQUA (-2775 2375);
FORCEPROP 1 LASTPIN (-2875 2300) $PN 2
J 2
(-2860 2315);
DISPLAY 0.617021 (-2860 2315);
PAINT ORANGE (-2860 2315);
FORCEPROP 1 LASTPIN (-2675 2300) $PN 1
J 2
(-2665 2315);
DISPLAY 0.617021 (-2665 2315);
PAINT ORANGE (-2665 2315);
FORCEPROP 1 LAST PART_NUMBER A36096-075
J 1
(-2700 2225);
DISPLAY 0.617021 (-2700 2225);
PAINT BLUE (-2700 2225);
FORCEPROP 1 LAST VALUE 2200PF
J 0
(-2750 2175);
DISPLAY 0.617021 (-2750 2175);
PAINT SKYBLUE (-2750 2175);
FORCEPROP 1 LAST VOLTAGE 50V
J 2
(-2750 2175);
DISPLAY 0.617021 (-2750 2175);
PAINT SKYBLUE (-2750 2175);
FORCEPROP 1 LAST PACK_TYPE 0402LF
J 1
(-2775 2075);
DISPLAY 0.617021 (-2775 2075);
PAINT SKYBLUE (-2775 2075);
FORCEPROP 1 LAST MATERIAL X7R
J 2
(-2750 2125);
DISPLAY 0.617021 (-2750 2125);
PAINT SKYBLUE (-2750 2125);
FORCEPROP 2 LAST SEC_TYPE 0402LF
J 0
(-2775 2550);
DISPLAY 1.021277 (-2775 2550);
PAINT ORANGE (-2775 2550);
DISPLAY INVISIBLE (-2775 2550);
FORCEPROP 2 LAST REUSE_ID 27
J 0
(-2775 2550);
DISPLAY 1.042553 (-2775 2550);
PAINT ORANGE (-2775 2550);
DISPLAY INVISIBLE (-2775 2550);
FORCEPROP 2 LAST SEC 1
J 0
(-2775 2550);
DISPLAY 0.680851 (-2775 2550);
PAINT MONO (-2775 2550);
DISPLAY INVISIBLE (-2775 2550);
FORCEPROP 2 LAST CDS_LIB mstr_discrete
J 0
(-2775 2300);
PAINT ORANGE (-2775 2300);
DISPLAY INVISIBLE (-2775 2300);
FORCEPROP 2 LAST CDS_LOCATION C4G10
J 1
(-2775 2375);
DISPLAY 0.617021 (-2775 2375);
PAINT AQUA (-2775 2375);
DISPLAY INVISIBLE (-2775 2375);
FORCEPROP 1 LAST PATH I274
J 2
(-2775 2500);
DISPLAY 0.978723 (-2775 2500);
PAINT WHITE (-2775 2500);
DISPLAY INVISIBLE (-2775 2500);
FORCEPROP 2 LAST ROOM PVPP_KLM_VR
J 2
(-2775 2425);
DISPLAY 0.765957 (-2775 2425);
PAINT GREEN (-2775 2425);
DISPLAY INVISIBLE (-2775 2425);
FORCEPROP 2 LAST BOM_COST PVPP_KLM_VR
J 0
(-2820 2460);
DISPLAY 1.042553 (-2820 2460);
PAINT WHITE (-2820 2460);
DISPLAY INVISIBLE (-2820 2460);
FORCEADD RES..1
(-6075 2675);
FORCEPROP 1 LASTPIN (-5975 2675) $PN 2
J 0
(-6013 2687);
DISPLAY 0.617021 (-6013 2687);
PAINT ORANGE (-6013 2687);
FORCEPROP 1 LAST LOCATION R4G4
J 0
(-6125 2725);
DISPLAY 0.617021 (-6125 2725);
PAINT AQUA (-6125 2725);
FORCEPROP 1 LAST VALUE 0.0
J 2
(-6175 2575);
DISPLAY 0.617021 (-6175 2575);
PAINT SKYBLUE (-6175 2575);
FORCEPROP 1 LAST MATERIAL CHIP
J 0
(-6075 2525);
DISPLAY 0.617021 (-6075 2525);
PAINT SKYBLUE (-6075 2525);
FORCEPROP 1 LAST PACK_TYPE 0402
J 0
(-6000 2575);
DISPLAY 0.617021 (-6000 2575);
PAINT SKYBLUE (-6000 2575);
FORCEPROP 1 LAST WATTAGE 1/16W
J 2
(-6100 2525);
DISPLAY 0.617021 (-6100 2525);
PAINT SKYBLUE (-6100 2525);
FORCEPROP 1 LAST TOLERANCE 5%
J 0
(-6125 2575);
DISPLAY 0.617021 (-6125 2575);
PAINT SKYBLUE (-6125 2575);
FORCEPROP 1 LAST PART_NUMBER G21497-005
J 0
(-6225 2625);
DISPLAY 0.617021 (-6225 2625);
PAINT BLUE (-6225 2625);
FORCEPROP 1 LASTPIN (-6175 2675) $PN 1
J 0
(-6163 2687);
DISPLAY 0.617021 (-6163 2687);
PAINT ORANGE (-6163 2687);
FORCEPROP 1 LAST PATH I275
J 0
(-6125 2825);
DISPLAY 0.978723 (-6125 2825);
PAINT WHITE (-6125 2825);
DISPLAY INVISIBLE (-6125 2825);
FORCEPROP 2 LAST SEC 1
J 0
(-6125 2875);
PAINT MONO (-6125 2875);
DISPLAY INVISIBLE (-6125 2875);
FORCEPROP 2 LAST SEC_TYPE 0402
J 0
(-6125 2875);
DISPLAY 1.021277 (-6125 2875);
PAINT ORANGE (-6125 2875);
DISPLAY INVISIBLE (-6125 2875);
FORCEPROP 2 LAST ROOM PVCCIN_CPU0_VR
J 0
(-6125 2775);
DISPLAY 1.361702 (-6125 2775);
PAINT ORANGE (-6125 2775);
DISPLAY INVISIBLE (-6125 2775);
FORCEPROP 2 LAST CDS_LIB mstr_discrete
J 0
(-6075 2675);
PAINT ORANGE (-6075 2675);
DISPLAY INVISIBLE (-6075 2675);
FORCEPROP 2 LAST CDS_LOCATION R4G4
J 0
(-6125 2725);
DISPLAY 0.617021 (-6125 2725);
PAINT AQUA (-6125 2725);
DISPLAY INVISIBLE (-6125 2725);
FORCEADD AGND_SCSI..1
(-1275 900);
FORCEPROP 3 LASTPIN (-1275 950) SIG_NAME AGND_PVPP_GHJ\g
J 0
(-1265 960);
DISPLAY 0.659574 (-1265 960);
PAINT MONO (-1265 960);
DISPLAY INVISIBLE (-1265 960);
FORCEPROP 1 LAST HDL_POWER AGND_PVPP_GHJ
J 1
(-1250 850);
DISPLAY 0.617021 (-1250 850);
PAINT GREEN (-1250 850);
FORCEPROP 1 LAST VOLTAGE 0.0V
J 0
(-1320 857);
DISPLAY 0.340426 (-1320 857);
PAINT SKYBLUE (-1320 857);
DISPLAY INVISIBLE (-1320 857);
FORCEPROP 2 LAST BOM_COST PVPP_KLM_VR
J 0
(-1425 850);
DISPLAY 1.042553 (-1425 850);
PAINT WHITE (-1425 850);
DISPLAY INVISIBLE (-1425 850);
FORCEPROP 2 LAST ROOM PVPP_KLM_VR
J 0
(-1425 850);
DISPLAY 1.042553 (-1425 850);
PAINT GREEN (-1425 850);
DISPLAY INVISIBLE (-1425 850);
FORCEPROP 2 LAST CDS_LIB mstr_symbols
J 0
(-1275 900);
PAINT ORANGE (-1275 900);
DISPLAY INVISIBLE (-1275 900);
FORCEPROP 1 LAST PATH I276
J 0
(-1200 900);
DISPLAY 0.872340 (-1200 900);
PAINT AQUA (-1200 900);
DISPLAY INVISIBLE (-1200 900);
FORCEPROP 1 LAST BODY_TYPE PLUMBING
J 0
(-1320 857);
DISPLAY 0.340426 (-1320 857);
PAINT GREEN (-1320 857);
DISPLAY INVISIBLE (-1320 857);
FORCEADD INDUCTOR..1
(-2175 3700);
FORCEPROP 1 LAST MATERIAL IND
J 0
(-2210 3640);
DISPLAY 0.617021 (-2210 3640);
PAINT SKYBLUE (-2210 3640);
FORCEPROP 1 LAST VALUE 0.47UH
J 2
(-2180 3765);
DISPLAY 0.617021 (-2180 3765);
PAINT SKYBLUE (-2180 3765);
FORCEPROP 1 LAST PACK_TYPE SM
J 0
(-2135 3765);
DISPLAY 0.617021 (-2135 3765);
PAINT SKYBLUE (-2135 3765);
FORCEPROP 1 LASTPIN (-2075 3700) $PN 2
J 2
(-2065 3710);
DISPLAY 0.617021 (-2065 3710);
PAINT WHITE (-2065 3710);
FORCEPROP 1 LASTPIN (-2275 3700) $PN 1
J 0
(-2275 3710);
DISPLAY 0.617021 (-2275 3710);
PAINT WHITE (-2275 3710);
FORCEPROP 1 LAST PART_NUMBER E13358-018
J 0
(-2200 3800);
DISPLAY 0.617021 (-2200 3800);
PAINT BLUE (-2200 3800);
FORCEPROP 1 LAST LOCATION L4G1
J 0
(-2350 3800);
DISPLAY 0.617021 (-2350 3800);
PAINT AQUA (-2350 3800);
FORCEPROP 0 LAST TOLERANCE 1%
J 0
(-2275 3850);
PAINT SKYBLUE (-2275 3850);
DISPLAY INVISIBLE (-2275 3850);
FORCEPROP 2 LAST SEC_TYPE SM
J 0
(-2275 3900);
DISPLAY 1.021277 (-2275 3900);
PAINT ORANGE (-2275 3900);
DISPLAY INVISIBLE (-2275 3900);
FORCEPROP 2 LAST REUSE_ID 30
J 0
(-2275 3900);
DISPLAY 1.042553 (-2275 3900);
PAINT ORANGE (-2275 3900);
DISPLAY INVISIBLE (-2275 3900);
FORCEPROP 2 LAST SEC 1
J 0
(-2275 3900);
DISPLAY 0.680851 (-2275 3900);
PAINT MONO (-2275 3900);
DISPLAY INVISIBLE (-2275 3900);
FORCEPROP 1 LAST PATH I277
J 0
(-2275 3850);
DISPLAY 0.978723 (-2275 3850);
PAINT ORANGE (-2275 3850);
DISPLAY INVISIBLE (-2275 3850);
FORCEPROP 2 LAST BOM_COST PVPP_GHJ_VR
J 0
(-2175 3700);
PAINT WHITE (-2175 3700);
DISPLAY INVISIBLE (-2175 3700);
FORCEPROP 2 LAST CDS_LIB mstr_discrete
J 0
(-2175 3700);
PAINT ORANGE (-2175 3700);
DISPLAY INVISIBLE (-2175 3700);
FORCEPROP 2 LAST ROOM PVPP_GHJ_VR
J 2
(-2175 3700);
PAINT GREEN (-2175 3700);
DISPLAY INVISIBLE (-2175 3700);
FORCEPROP 2 LAST CDS_LOCATION L4G1
J 0
(-2225 3750);
DISPLAY 0.617021 (-2225 3750);
PAINT AQUA (-2225 3750);
DISPLAY INVISIBLE (-2225 3750);
FORCEADD SC22U16V5MX-4-GP..1
(-7000 3950);
FORCEPROP 2 LAST ATTRIBUTE 22UF
J 0
(-6900 3975);
DISPLAY 0.638298 (-6900 3975);
PAINT GREEN (-6900 3975);
FORCEPROP 2 LAST TOLERANCE 20%
J 0
(-6900 3925);
DISPLAY 0.638298 (-6900 3925);
PAINT GREEN (-6900 3925);
FORCEPROP 2 LAST RATED 16V
J 0
(-6900 3875);
DISPLAY 0.638298 (-6900 3875);
PAINT GREEN (-6900 3875);
FORCEPROP 2 LAST TYPE X6S
J 0
(-6900 3825);
DISPLAY 0.638298 (-6900 3825);
PAINT GREEN (-6900 3825);
FORCEPROP 2 LAST PACK_SIZE 0805
J 0
(-6900 3775);
DISPLAY 0.638298 (-6900 3775);
PAINT GREEN (-6900 3775);
FORCEPROP 2 LASTPIN (-7000 3875) $PN 2
R 1
J 2
(-7010 3865);
DISPLAY 0.808511 (-7010 3865);
PAINT ORANGE (-7010 3865);
FORCEPROP 2 LASTPIN (-7000 4025) $PN 1
R 1
J 0
(-7010 4035);
DISPLAY 0.808511 (-7010 4035);
PAINT ORANGE (-7010 4035);
FORCEPROP 1 LAST VALUE SC22U16V5MX-4-GP
R 1
J 0
(-6925 3745);
DISPLAY 0.617021 (-6925 3745);
PAINT GREEN (-6925 3745);
FORCEPROP 1 LAST LOCATION C22W6
J 0
(-6900 4035);
DISPLAY 0.617021 (-6900 4035);
PAINT GREEN (-6900 4035);
FORCEPROP 1 LAST PATH I278
J 0
(-7000 3950);
DISPLAY 0.617021 (-7000 3950);
PAINT GREEN (-7000 3950);
DISPLAY INVISIBLE (-7000 3950);
FORCEPROP 1 LAST PACK_TYPE SMD-BCG5
J 0
(-7000 3950);
DISPLAY 0.617021 (-7000 3950);
PAINT GREEN (-7000 3950);
DISPLAY INVISIBLE (-7000 3950);
FORCEPROP 2 LAST SEC 1
J 0
(-6975 4025);
DISPLAY 0.680851 (-6975 4025);
PAINT MONO (-6975 4025);
DISPLAY INVISIBLE (-6975 4025);
FORCEPROP 2 LAST SEC_TYPE SMD-BCG5
J 0
(-6975 4025);
DISPLAY 1.021277 (-6975 4025);
PAINT ORANGE (-6975 4025);
DISPLAY INVISIBLE (-6975 4025);
FORCEPROP 1 LAST PART_NUMBER 078.22611.0811
J 0
(-7000 3950);
DISPLAY 0.617021 (-7000 3950);
PAINT GREEN (-7000 3950);
DISPLAY INVISIBLE (-7000 3950);
FORCEPROP 2 LAST CDS_LIB w_hdl
J 0
(-7000 3950);
PAINT MONO (-7000 3950);
DISPLAY INVISIBLE (-7000 3950);
FORCEPROP 1 LAST CDS_LMAN_SYM_OUTLINE -50,25,50,-25
J 0
(-7000 3950);
DISPLAY 0.468085 (-7000 3950);
PAINT GREEN (-7000 3950);
DISPLAY INVISIBLE (-7000 3950);
FORCEADD GND..1
(-7000 3725);
FORCEPROP 3 LASTPIN (-7000 3775) SIG_NAME GND\g
J 0
(-6990 3785);
DISPLAY 0.659574 (-6990 3785);
PAINT MONO (-6990 3785);
DISPLAY INVISIBLE (-6990 3785);
FORCEPROP 2 LAST CDS_LIB mstr_symbols
J 0
(-7000 3725);
PAINT MONO (-7000 3725);
DISPLAY INVISIBLE (-7000 3725);
FORCEPROP 2 LAST BOM_COST PVPP_KLM_VR
J 0
(-7850 3800);
DISPLAY 1.042553 (-7850 3800);
PAINT WHITE (-7850 3800);
DISPLAY INVISIBLE (-7850 3800);
FORCEPROP 2 LAST ROOM PVPP_KLM_VR
J 0
(-7575 3800);
DISPLAY 1.042553 (-7575 3800);
PAINT GREEN (-7575 3800);
DISPLAY INVISIBLE (-7575 3800);
FORCEPROP 1 LAST VOLTAGE 0
J 0
(-7000 3725);
PAINT SKYBLUE (-7000 3725);
DISPLAY INVISIBLE (-7000 3725);
FORCEPROP 1 LAST SIZE 1B
J 0
(-6925 3675);
DISPLAY 0.872340 (-6925 3675);
PAINT GREEN (-6925 3675);
DISPLAY INVISIBLE (-6925 3675);
FORCEPROP 1 LAST PATH I279
J 0
(-6925 3725);
DISPLAY 0.872340 (-6925 3725);
PAINT AQUA (-6925 3725);
DISPLAY INVISIBLE (-6925 3725);
FORCEPROP 1 LAST BODY_TYPE PLUMBING
J 0
(-7045 3682);
DISPLAY 0.340426 (-7045 3682);
PAINT GREEN (-7045 3682);
DISPLAY INVISIBLE (-7045 3682);
FORCEPROP 1 LAST HDL_POWER GND
J 0
(-7000 3875);
DISPLAY 0.872340 (-7000 3875);
PAINT GREEN (-7000 3875);
DISPLAY INVISIBLE (-7000 3875);
FORCEADD SC22U16V5MX-4-GP..1
(-7300 3950);
FORCEPROP 2 LASTPIN (-7300 3875) $PN 2
R 1
J 2
(-7310 3865);
DISPLAY 0.808511 (-7310 3865);
PAINT ORANGE (-7310 3865);
FORCEPROP 1 LAST VALUE SC22U16V5MX-4-GP
R 1
J 0
(-7225 3745);
DISPLAY 0.617021 (-7225 3745);
PAINT GREEN (-7225 3745);
FORCEPROP 1 LAST LOCATION C4G5
J 0
(-7200 4035);
DISPLAY 0.617021 (-7200 4035);
PAINT GREEN (-7200 4035);
FORCEPROP 2 LAST PACK_SIZE 0805
J 0
(-7200 3775);
DISPLAY 0.638298 (-7200 3775);
PAINT GREEN (-7200 3775);
FORCEPROP 2 LAST TYPE X6S
J 0
(-7200 3825);
DISPLAY 0.638298 (-7200 3825);
PAINT GREEN (-7200 3825);
FORCEPROP 2 LAST RATED 16V
J 0
(-7200 3875);
DISPLAY 0.638298 (-7200 3875);
PAINT GREEN (-7200 3875);
FORCEPROP 2 LAST TOLERANCE 20%
J 0
(-7200 3925);
DISPLAY 0.638298 (-7200 3925);
PAINT GREEN (-7200 3925);
FORCEPROP 2 LAST ATTRIBUTE 22UF
J 0
(-7200 3975);
DISPLAY 0.638298 (-7200 3975);
PAINT GREEN (-7200 3975);
FORCEPROP 2 LASTPIN (-7300 4025) $PN 1
R 1
J 0
(-7310 4035);
DISPLAY 0.808511 (-7310 4035);
PAINT ORANGE (-7310 4035);
FORCEPROP 1 LAST PACK_TYPE SMD-BCG5
J 0
(-7300 3950);
DISPLAY 0.617021 (-7300 3950);
PAINT GREEN (-7300 3950);
DISPLAY INVISIBLE (-7300 3950);
FORCEPROP 2 LAST SEC 1
J 0
(-7275 4025);
DISPLAY 0.680851 (-7275 4025);
PAINT MONO (-7275 4025);
DISPLAY INVISIBLE (-7275 4025);
FORCEPROP 2 LAST SEC_TYPE SMD-BCG5
J 0
(-7275 4025);
DISPLAY 1.021277 (-7275 4025);
PAINT ORANGE (-7275 4025);
DISPLAY INVISIBLE (-7275 4025);
FORCEPROP 1 LAST PART_NUMBER 078.22611.0811
J 0
(-7300 3950);
DISPLAY 0.617021 (-7300 3950);
PAINT GREEN (-7300 3950);
DISPLAY INVISIBLE (-7300 3950);
FORCEPROP 2 LAST CDS_LIB w_hdl
J 0
(-7300 3950);
PAINT MONO (-7300 3950);
DISPLAY INVISIBLE (-7300 3950);
FORCEPROP 1 LAST CDS_LMAN_SYM_OUTLINE -50,25,50,-25
J 0
(-7300 3950);
DISPLAY 0.468085 (-7300 3950);
PAINT GREEN (-7300 3950);
DISPLAY INVISIBLE (-7300 3950);
FORCEPROP 1 LAST PATH I280
J 0
(-7300 3950);
DISPLAY 0.617021 (-7300 3950);
PAINT GREEN (-7300 3950);
DISPLAY INVISIBLE (-7300 3950);
FORCEADD GND..1
(-7300 3725);
FORCEPROP 3 LASTPIN (-7300 3775) SIG_NAME GND\g
J 0
(-7290 3785);
DISPLAY 0.659574 (-7290 3785);
PAINT MONO (-7290 3785);
DISPLAY INVISIBLE (-7290 3785);
FORCEPROP 1 LAST PATH I281
J 0
(-7225 3725);
DISPLAY 0.872340 (-7225 3725);
PAINT AQUA (-7225 3725);
DISPLAY INVISIBLE (-7225 3725);
FORCEPROP 1 LAST SIZE 1B
J 0
(-7225 3675);
DISPLAY 0.872340 (-7225 3675);
PAINT GREEN (-7225 3675);
DISPLAY INVISIBLE (-7225 3675);
FORCEPROP 1 LAST VOLTAGE 0
J 0
(-7300 3725);
PAINT SKYBLUE (-7300 3725);
DISPLAY INVISIBLE (-7300 3725);
FORCEPROP 2 LAST ROOM PVPP_KLM_VR
J 0
(-7875 3800);
DISPLAY 1.042553 (-7875 3800);
PAINT GREEN (-7875 3800);
DISPLAY INVISIBLE (-7875 3800);
FORCEPROP 2 LAST BOM_COST PVPP_KLM_VR
J 0
(-8150 3800);
DISPLAY 1.042553 (-8150 3800);
PAINT WHITE (-8150 3800);
DISPLAY INVISIBLE (-8150 3800);
FORCEPROP 2 LAST CDS_LIB mstr_symbols
J 0
(-7300 3725);
PAINT MONO (-7300 3725);
DISPLAY INVISIBLE (-7300 3725);
FORCEPROP 1 LAST BODY_TYPE PLUMBING
J 0
(-7345 3682);
DISPLAY 0.340426 (-7345 3682);
PAINT GREEN (-7345 3682);
DISPLAY INVISIBLE (-7345 3682);
FORCEPROP 1 LAST HDL_POWER GND
J 0
(-7300 3875);
DISPLAY 0.872340 (-7300 3875);
PAINT GREEN (-7300 3875);
DISPLAY INVISIBLE (-7300 3875);
FORCEADD RES..1
(-4075 4050);
FORCEPROP 1 LASTPIN (-4175 4050) $PN 1
J 0
(-4163 4062);
DISPLAY 0.787234 (-4163 4062);
PAINT ORANGE (-4163 4062);
FORCEPROP 1 LASTPIN (-3975 4050) $PN 2
J 0
(-4013 4062);
DISPLAY 0.787234 (-4013 4062);
PAINT ORANGE (-4013 4062);
FORCEPROP 1 LAST PART_NUMBER G22178-002
J 0
(-4200 4000);
DISPLAY 0.617021 (-4200 4000);
PAINT BLUE (-4200 4000);
FORCEPROP 1 LAST VALUE 0
J 0
(-4200 3950);
DISPLAY 0.617021 (-4200 3950);
PAINT SKYBLUE (-4200 3950);
FORCEPROP 1 LAST TOLERANCE 5.0%
J 0
(-4125 3950);
DISPLAY 0.617021 (-4125 3950);
PAINT SKYBLUE (-4125 3950);
FORCEPROP 1 LAST PACK_TYPE 0603
J 0
(-4200 3900);
DISPLAY 0.617021 (-4200 3900);
PAINT SKYBLUE (-4200 3900);
FORCEPROP 1 LAST WATTAGE 1/10W
J 0
(-4075 3900);
DISPLAY 0.617021 (-4075 3900);
PAINT SKYBLUE (-4075 3900);
FORCEPROP 1 LAST LOCATION R4G24
J 0
(-4175 4100);
DISPLAY 0.617021 (-4175 4100);
PAINT AQUA (-4175 4100);
FORCEPROP 0 LAST CDS_LOCATION R4G24
J 0
(-4000 4050);
PAINT MONO (-4000 4050);
DISPLAY INVISIBLE (-4000 4050);
FORCEPROP 1 LAST MATERIAL CHIP
J 0
(-4075 3900);
DISPLAY 0.617021 (-4075 3900);
PAINT SKYBLUE (-4075 3900);
DISPLAY INVISIBLE (-4075 3900);
FORCEPROP 0 LAST ROOM NIC_SPRV
J 0
(-3975 4175);
DISPLAY 1.021277 (-3975 4175);
PAINT ORANGE (-3975 4175);
DISPLAY INVISIBLE (-3975 4175);
FORCEPROP 0 LAST BOM_COST NT_GBE_BASE
J 0
(-3975 4275);
DISPLAY 1.021277 (-3975 4275);
PAINT ORANGE (-3975 4275);
DISPLAY INVISIBLE (-3975 4275);
FORCEPROP 2 LAST CDS_LIB mstr_discrete
J 0
(-4075 4050);
PAINT MONO (-4075 4050);
DISPLAY INVISIBLE (-4075 4050);
FORCEPROP 2 LAST SEC_TYPE 0603
J 0
(-4125 4250);
DISPLAY 1.021277 (-4125 4250);
PAINT ORANGE (-4125 4250);
DISPLAY INVISIBLE (-4125 4250);
FORCEPROP 0 LAST SEC 1
J 0
(-4325 4150);
DISPLAY 0.680851 (-4325 4150);
PAINT MONO (-4325 4150);
DISPLAY INVISIBLE (-4325 4150);
FORCEPROP 0 LAST CDS_SEC 1
J 0
(-4000 4050);
PAINT MONO (-4000 4050);
DISPLAY INVISIBLE (-4000 4050);
FORCEPROP 1 LAST PATH I282
J 0
(-4125 4200);
DISPLAY 0.978723 (-4125 4200);
PAINT WHITE (-4125 4200);
DISPLAY INVISIBLE (-4125 4200);
FORCEADD RES..2
(-1275 1225);
FORCEPROP 1 LAST PART_NUMBER G21796-161
J 0
(-1235 1100);
DISPLAY 0.617021 (-1235 1100);
PAINT BLUE (-1235 1100);
FORCEPROP 1 LAST PACK_TYPE 0402
J 0
(-1235 1050);
DISPLAY 0.617021 (-1235 1050);
PAINT SKYBLUE (-1235 1050);
FORCEPROP 1 LAST MATERIAL CHIP
J 0
(-1235 1150);
DISPLAY 0.617021 (-1235 1150);
PAINT SKYBLUE (-1235 1150);
FORCEPROP 1 LAST WATTAGE 1/16W
J 0
(-1235 1200);
DISPLAY 0.617021 (-1235 1200);
PAINT SKYBLUE (-1235 1200);
FORCEPROP 1 LAST TOLERANCE 1%
J 0
(-1230 1250);
DISPLAY 0.617021 (-1230 1250);
PAINT SKYBLUE (-1230 1250);
FORCEPROP 1 LAST VALUE 6.19K
J 0
(-1230 1300);
DISPLAY 0.617021 (-1230 1300);
PAINT SKYBLUE (-1230 1300);
FORCEPROP 1 LASTPIN (-1275 1325) $PN 1
J 0
(-1270 1287);
DISPLAY 0.617021 (-1270 1287);
PAINT ORANGE (-1270 1287);
FORCEPROP 1 LASTPIN (-1275 1125) $PN 2
J 0
(-1270 1135);
DISPLAY 0.617021 (-1270 1135);
PAINT ORANGE (-1270 1135);
FORCEPROP 1 LAST LOCATION R4G9
J 0
(-1230 1350);
DISPLAY 0.617021 (-1230 1350);
PAINT AQUA (-1230 1350);
FORCEPROP 2 LAST CDS_LOCATION R4G9
J 0
(-1230 1350);
DISPLAY 0.617021 (-1230 1350);
PAINT AQUA (-1230 1350);
DISPLAY INVISIBLE (-1230 1350);
FORCEPROP 0 LAST BOM_COST IO_SLOT
J 0
(-1225 1550);
DISPLAY 1.021277 (-1225 1550);
PAINT ORANGE (-1225 1550);
DISPLAY INVISIBLE (-1225 1550);
FORCEPROP 2 LAST SEC 1
J 0
(-1225 1450);
DISPLAY 0.680851 (-1225 1450);
PAINT MONO (-1225 1450);
DISPLAY INVISIBLE (-1225 1450);
FORCEPROP 2 LAST SEC_TYPE 0402
J 0
(-1225 1450);
DISPLAY 1.021277 (-1225 1450);
PAINT ORANGE (-1225 1450);
DISPLAY INVISIBLE (-1225 1450);
FORCEPROP 0 LAST ROOM IO_SLOT
J 0
(-1225 1450);
DISPLAY 1.021277 (-1225 1450);
PAINT ORANGE (-1225 1450);
DISPLAY INVISIBLE (-1225 1450);
FORCEPROP 2 LAST CDS_LIB mstr_discrete
J 0
(-1275 1225);
PAINT ORANGE (-1275 1225);
DISPLAY INVISIBLE (-1275 1225);
FORCEPROP 0 LAST CDS_SEC 1
J 0
(-1225 1400);
PAINT MONO (-1225 1400);
DISPLAY INVISIBLE (-1225 1400);
FORCEPROP 1 LAST PATH I283
J 0
(-1225 1400);
DISPLAY 0.978723 (-1225 1400);
PAINT WHITE (-1225 1400);
DISPLAY INVISIBLE (-1225 1400);
FORCEADD RES..2
R 2
(-4675 1500);
FORCEPROP 1 LAST LOCATION R4G11
J 2
(-4720 1625);
DISPLAY 0.617021 (-4720 1625);
PAINT AQUA (-4720 1625);
FORCEPROP 0 LAST NEW_VALUE 3.9K
J 0
(-5075 1225);
DISPLAY 0.638298 (-5075 1225);
PAINT BROWN (-5075 1225);
DISPLAY BOTH (-5075 1225);
FORCEPROP 1 LAST TOLERANCE 1.0%
J 2
(-4720 1525);
DISPLAY 0.617021 (-4720 1525);
PAINT SKYBLUE (-4720 1525);
FORCEPROP 1 LASTPIN (-4675 1600) $PN 1
J 2
(-4680 1562);
DISPLAY 0.617021 (-4680 1562);
PAINT WHITE (-4680 1562);
FORCEPROP 1 LASTPIN (-4675 1400) $PN 2
J 2
(-4680 1410);
DISPLAY 0.617021 (-4680 1410);
PAINT WHITE (-4680 1410);
FORCEPROP 1 LAST WATTAGE 1/16W
J 2
(-4715 1475);
DISPLAY 0.617021 (-4715 1475);
PAINT SKYBLUE (-4715 1475);
FORCEPROP 0 LAST CONFIG 64.39015.6DL
J 0
(-5075 1275);
DISPLAY 0.638298 (-5075 1275);
PAINT BROWN (-5075 1275);
DISPLAY BOTH (-5075 1275);
FORCEPROP 1 LAST PACK_TYPE 0402
J 2
(-4715 1325);
DISPLAY 0.617021 (-4715 1325);
PAINT SKYBLUE (-4715 1325);
FORCEPROP 1 LAST MATERIAL CHIP
J 2
(-4715 1425);
DISPLAY 0.617021 (-4715 1425);
PAINT SKYBLUE (-4715 1425);
FORCEPROP 2 LAST CDS_SEC 1
J 2
(-4575 1875);
DISPLAY 1.042553 (-4575 1875);
PAINT ORANGE (-4575 1875);
DISPLAY INVISIBLE (-4575 1875);
FORCEPROP 2 LAST $SEC 1
J 0
(-4725 1725);
DISPLAY 0.680851 (-4725 1725);
PAINT MONO (-4725 1725);
DISPLAY INVISIBLE (-4725 1725);
FORCEPROP 2 LAST CDS_LIB mstr_discrete
J 2
(-4675 1500);
PAINT MONO (-4675 1500);
DISPLAY INVISIBLE (-4675 1500);
FORCEPROP 2 LAST BOM_COST PVPP_KLM_VR
J 2
(-4675 1500);
PAINT WHITE (-4675 1500);
DISPLAY INVISIBLE (-4675 1500);
FORCEPROP 2 LAST ROOM PVPP_KLM_VR
J 2
(-4675 1500);
PAINT GREEN (-4675 1500);
DISPLAY INVISIBLE (-4675 1500);
FORCEPROP 1 LAST VALUE 7.87K
J 2
(-4720 1575);
DISPLAY 0.617021 (-4720 1575);
PAINT SKYBLUE (-4720 1575);
DISPLAY INVISIBLE (-4720 1575);
FORCEPROP 1 LAST PATH I284
J 2
(-4725 1675);
DISPLAY 0.978723 (-4725 1675);
PAINT WHITE (-4725 1675);
DISPLAY INVISIBLE (-4725 1675);
FORCEPROP 1 LAST PART_NUMBER G21796-242
J 2
(-4715 1375);
DISPLAY 0.617021 (-4715 1375);
PAINT BLUE (-4715 1375);
DISPLAY INVISIBLE (-4715 1375);
FORCEPROP 2 LAST CDS_LOCATION R4G11
J 2
(-4720 1625);
DISPLAY 0.617021 (-4720 1625);
PAINT AQUA (-4720 1625);
DISPLAY INVISIBLE (-4720 1625);
FORCEADD INTEL_CORP_BPAGE..1
(-375 -75);
FORCEPROP 1 LAST CDS_CON_LAST_MODIFIED Fri Jun 16 17:49:23 2017
J 0
(-1800 250);
DISPLAY 0.489362 (-1800 250);
PAINT GREEN (-1800 250);
DISPLAY INVISIBLE (-1800 250);
FORCEPROP 1 LAST CUSTOM_TXT_CDS <CURRENT_DESIGN_SHEET> OF <TOTAL_DESIGN_SHEETS>
J 0
(-875 -50);
PAINT ORANGE (-875 -50);
FORCEPROP 1 LAST CUSTOM_TXT_CDS <CON_LAST_MODIFIED>
J 0
(-4375 25);
PAINT ORANGE (-4375 25);
FORCEPROP 2 LAST CUSTOM_TXT_CDS <XR_PAGE_TITLE>
J 0
(-8265 5175);
DISPLAY 0.638298 (-8265 5175);
PAINT PINK (-8265 5175);
DISPLAY INVISIBLE (-8265 5175);
FORCEPROP 1 LAST SCH_TITLE VPP GHJ VR
J 0
(-8250 50);
DISPLAY 1.212766 (-8250 50);
PAINT GREEN (-8250 50);
FORCEPROP 2 LAST PAGE_BORDER TRUE
J 0
(-8265 5175);
DISPLAY 0.425532 (-8265 5175);
PAINT PINK (-8265 5175);
DISPLAY INVISIBLE (-8265 5175);
FORCEPROP 2 LAST CDS_LIB mstr_symbols
J 0
(-375 -75);
DISPLAY 0.489362 (-375 -75);
PAINT ORANGE (-375 -75);
DISPLAY INVISIBLE (-375 -75);
FORCEPROP 1 LAST COMMENT_BODY TRUE
J 0
(-363 -63);
DISPLAY 0.234043 (-363 -63);
PAINT GREEN (-363 -63);
DISPLAY INVISIBLE (-363 -63);
FORCEPROP 2 LAST CDS_XR_PAGE_TITLE CR-233 : @BASEBOARD_FAB2_LIB.BASEBOARD_FAB2(SCH_1):PAGE233
J 0
(-8265 5175);
DISPLAY 0.638298 (-8265 5175);
PAINT PINK (-8265 5175);
DISPLAY INVISIBLE (-8265 5175);
FORCEADD DNS..2
(-6495 2195);
PAINT RED (-6495 2195);
FORCEPROP 2 LAST CDS_LIB mstr_misc
J 0
(-6495 2195);
PAINT ORANGE (-6495 2195);
DISPLAY INVISIBLE (-6495 2195);
FORCEPROP 1 LAST COMMENT_BODY TRUE
R 1
J 0
(-6420 1970);
DISPLAY 0.872340 (-6420 1970);
PAINT GREEN (-6420 1970);
DISPLAY INVISIBLE (-6420 1970);
FORCEADD DNS..2
(-2445 3470);
PAINT RED (-2445 3470);
FORCEPROP 2 LAST CDS_LIB mstr_misc
J 0
(-2445 3470);
PAINT ORANGE (-2445 3470);
DISPLAY INVISIBLE (-2445 3470);
FORCEPROP 1 LAST COMMENT_BODY TRUE
R 1
J 0
(-2370 3245);
DISPLAY 0.872340 (-2370 3245);
PAINT GREEN (-2370 3245);
DISPLAY INVISIBLE (-2370 3245);
FORCEADD DNS..2
(-2445 3095);
PAINT RED (-2445 3095);
FORCEPROP 2 LAST CDS_LIB mstr_misc
J 0
(-2445 3095);
PAINT ORANGE (-2445 3095);
DISPLAY INVISIBLE (-2445 3095);
FORCEPROP 1 LAST COMMENT_BODY TRUE
R 1
J 0
(-2370 2870);
DISPLAY 0.872340 (-2370 2870);
PAINT GREEN (-2370 2870);
DISPLAY INVISIBLE (-2370 2870);
WIRE 16 -1 (-8100 900)(-8100 950);
WIRE 16 -1 (-8100 900)(-7875 900);
WIRE 16 -1 (-8150 900)(-8100 900);
WIRE 16 -1 (-8150 900)(-8150 825);
WIRE 16 -1 (-7875 900)(-7600 900);
WIRE 16 -1 (-7875 825)(-7875 900);
WIRE 16 -1 (-7325 900)(-7600 900);
WIRE 16 -1 (-7600 825)(-7600 900);
WIRE 16 -1 (-7050 900)(-7325 900);
WIRE 16 -1 (-7325 825)(-7325 900);
WIRE 16 -1 (-6750 900)(-7050 900);
WIRE 16 -1 (-7050 825)(-7050 900);
WIRE 16 -1 (-6475 900)(-6750 900);
WIRE 16 -1 (-6750 825)(-6750 900);
WIRE 16 -1 (-6175 900)(-6475 900);
WIRE 16 -1 (-6475 900)(-6475 825);
WIRE 16 -1 (-5875 900)(-6175 900);
WIRE 16 -1 (-6175 825)(-6175 900);
WIRE 16 -1 (-5600 900)(-5875 900);
WIRE 16 -1 (-5875 825)(-5875 900);
WIRE 16 -1 (-5325 900)(-5600 900);
WIRE 16 -1 (-5600 825)(-5600 900);
WIRE 16 -1 (-5000 900)(-5325 900);
WIRE 16 -1 (-5325 825)(-5325 900);
WIRE 16 -1 (-5000 825)(-5000 900);
WIRE 16 -1 (-8150 350)(-8150 325);
WIRE 16 -1 (-8150 350)(-7875 350);
WIRE 16 -1 (-8150 625)(-8150 350);
WIRE 16 -1 (-7875 350)(-7600 350);
WIRE 16 -1 (-7875 625)(-7875 350);
WIRE 16 -1 (-7600 350)(-7325 350);
WIRE 16 -1 (-7600 625)(-7600 350);
WIRE 16 -1 (-7050 350)(-7325 350);
WIRE 16 -1 (-7325 625)(-7325 350);
WIRE 16 -1 (-7050 350)(-6750 350);
WIRE 16 -1 (-7050 625)(-7050 350);
WIRE 16 -1 (-6750 350)(-6475 350);
WIRE 16 -1 (-6750 625)(-6750 350);
WIRE 16 -1 (-6475 350)(-6175 350);
WIRE 16 -1 (-6475 625)(-6475 350);
WIRE 16 -1 (-6175 350)(-5875 350);
WIRE 16 -1 (-6175 625)(-6175 350);
WIRE 16 -1 (-5875 350)(-5600 350);
WIRE 16 -1 (-5875 625)(-5875 350);
WIRE 16 -1 (-5325 350)(-5600 350);
WIRE 16 -1 (-5600 625)(-5600 350);
WIRE 16 -1 (-5000 350)(-5325 350);
WIRE 16 -1 (-5325 625)(-5325 350);
WIRE 16 -1 (-5000 625)(-5000 350);
WIRE 16 -1 (-1400 500)(-1400 550);
WIRE 16 -1 (-1400 550)(-1200 550);
WIRE 16 -1 (-850 500)(-850 550);
WIRE 16 -1 (-850 550)(-1000 550);
WIRE 16 -1 (-725 3775)(-725 3700);
WIRE 16 -1 (-725 3700)(-775 3700);
WIRE 16 -1 (-525 3700)(-725 3700);
WIRE 16 -1 (-525 3700)(-525 3200);
WIRE 16 -1 (-1075 3700)(-775 3700);
WIRE 16 -1 (-775 3700)(-775 3625);
WIRE 16 -1 (-1075 3700)(-1400 3700);
WIRE 16 -1 (-1075 3700)(-1075 3625);
WIRE 16 -1 (-1275 3200)(-525 3200);
WIRE 16 -1 (-1275 3200)(-1275 3000);
WIRE 16 -1 (-1400 3700)(-1700 3700);
WIRE 16 -1 (-1400 3600)(-1400 3700);
WIRE 16 -1 (-2000 3700)(-1700 3700);
WIRE 16 -1 (-1700 3700)(-1700 3600);
WIRE 16 -1 (-2075 3700)(-2000 3700);
WIRE 16 -1 (-2000 3625)(-2000 3700);
WIRE 16 -1 (-7100 1950)(-7100 2100);
WIRE 16 -1 (-4150 1325)(-4150 1200);
WIRE 16 -1 (-5000 3825)(-5000 3900);
WIRE 16 -1 (-7775 4300)(-7775 4150);
WIRE 16 -1 (-7775 4150)(-7700 4150);
WIRE 16 -1 (-3800 475)(-3800 375);
WIRE 16 -1 (-3000 1875)(-3000 1825);
WIRE 16 -1 (-3000 1925)(-3000 1875);
WIRE 16 -1 (-3225 1875)(-3000 1875);
WIRE 16 -1 (-3000 1975)(-3000 1925);
WIRE 16 -1 (-3225 1925)(-3000 1925);
WIRE 16 -1 (-3000 2025)(-3000 1975);
WIRE 16 -1 (-3225 1975)(-3000 1975);
WIRE 16 -1 (-3000 2075)(-3000 2025);
WIRE 16 -1 (-3225 2025)(-3000 2025);
WIRE 16 -1 (-3000 2125)(-3000 2075);
WIRE 16 -1 (-3225 2075)(-3000 2075);
WIRE 16 -1 (-3000 2175)(-3000 2125);
WIRE 16 -1 (-3225 2125)(-3000 2125);
WIRE 16 -1 (-3000 2225)(-3000 2175);
WIRE 16 -1 (-3225 2175)(-3000 2175);
WIRE 16 -1 (-3000 2275)(-3000 2225);
WIRE 16 -1 (-3225 2225)(-3000 2225);
WIRE 16 -1 (-3000 2325)(-3000 2275);
WIRE 16 -1 (-3225 2275)(-3000 2275);
WIRE 16 -1 (-3000 2375)(-3000 2325);
WIRE 16 -1 (-3225 2325)(-3000 2325);
WIRE 16 -1 (-3000 2425)(-3000 2375);
WIRE 16 -1 (-3225 2375)(-3000 2375);
WIRE 16 -1 (-3000 2475)(-3000 2425);
WIRE 16 -1 (-3225 2425)(-3000 2425);
WIRE 16 -1 (-3000 2525)(-3000 2475);
WIRE 16 -1 (-3225 2475)(-3000 2475);
WIRE 16 -1 (-3000 2575)(-3000 2525);
WIRE 16 -1 (-3225 2525)(-3000 2525);
WIRE 16 -1 (-3225 2575)(-3000 2575);
WIRE 16 -1 (-2450 3000)(-2450 2950);
WIRE 16 -1 (-2000 3375)(-2000 3425);
WIRE 16 -1 (-1700 3225)(-1700 3400);
WIRE 16 -1 (-1075 3375)(-1075 3425);
WIRE 16 -1 (-775 3375)(-775 3425);
WIRE 16 -1 (-6500 1950)(-6500 2100);
WIRE 16 -1 (-5800 2100)(-5800 2250);
WIRE 16 -1 (-5000 1925)(-5000 1850);
WIRE 16 -1 (-4675 1400)(-4675 1300);
WIRE 16 -1 (-4300 1750)(-4300 1875);
WIRE 16 -1 (-4300 1875)(-4225 1875);
WIRE 16 -1 (-5050 3225)(-5050 3150);
WIRE 16 -1 (-5300 2625)(-5300 2775);
WIRE 16 -1 (-5300 2775)(-4225 2775);
WIRE 16 -1 (-1400 3225)(-1400 3400);
WIRE 16 -1 (-6600 3850)(-6600 3900);
WIRE 16 -1 (-6250 3850)(-6250 3900);
WIRE 16 -1 (-5875 3850)(-5875 3900);
WIRE 16 -1 (-5450 3850)(-5450 3900);
WIRE 16 -1 (-1275 950)(-1275 1125);
WIRE 16 -1 (-7000 3875)(-7000 3775);
WIRE 16 -1 (-7300 3875)(-7300 3775);
WIRE 16 2175 (-4700 200)(-8275 200);
WIRE 16 2175 (-4700 1100)(-4700 200);
WIRE 16 2175 (-8275 200)(-8275 1100);
WIRE 16 2175 (-8275 1100)(-4700 1100);
WIRE 16 -1 (-4225 2975)(-4650 2975);
WIRE 16 -1 (-4650 2975)(-4650 3025);
WIRE 16 -1 (-4225 3025)(-4650 3025);
WIRE 16 -1 (-4650 3025)(-4650 3075);
WIRE 16 -1 (-4225 3075)(-4650 3075);
WIRE 16 -1 (-4650 3075)(-4650 3125);
WIRE 16 -1 (-4225 3125)(-4650 3125);
WIRE 16 -1 (-7300 4025)(-7300 4150);
WIRE 16 -1 (-7500 4150)(-7300 4150);
WIRE 16 -1 (-4650 3125)(-4650 3175);
WIRE 16 -1 (-4225 3175)(-4650 3175);
WIRE 16 -1 (-4650 3175)(-4650 3225);
WIRE 16 -1 (-4225 3225)(-4650 3225);
WIRE 16 -1 (-7000 4150)(-7000 4025);
WIRE 16 -1 (-7300 4150)(-7000 4150);
WIRE 16 -1 (-6600 4150)(-7000 4150);
WIRE 16 -1 (-6600 4100)(-6600 4150);
WIRE 16 -1 (-4650 3225)(-4650 3275);
WIRE 16 -1 (-4225 3275)(-4650 3275);
WIRE 16 -1 (-4650 3275)(-4650 3325);
WIRE 16 -1 (-4650 3325)(-4225 3325);
WIRE 16 -1 (-6600 4150)(-6250 4150);
WIRE 16 -1 (-6250 4100)(-6250 4150);
WIRE 16 -1 (-5875 4150)(-6250 4150);
WIRE 16 -1 (-5875 4100)(-5875 4150);
WIRE 16 -1 (-4650 3425)(-4650 3325);
WIRE 16 -1 (-4225 3425)(-4650 3425);
WIRE 16 -1 (-5050 3425)(-5050 3525);
WIRE 16 -1 (-5050 3525)(-4650 3525);
WIRE 16 -1 (-4650 3525)(-4650 3425);
WIRE 16 -1 (-5450 4150)(-5875 4150);
FORCEPROP 0 LAST SIG_NAME VR_FET_SW_P12V_STBY_PVPP_GHJ
J 0
(-5835 4160);
DISPLAY 0.617021 (-5835 4160);
PAINT ORANGE (-5835 4160);
FORCEPROP 2 LASTPROP $XRERR UNIQUE?
J 0
(-6075 4160);
DISPLAY 0.638298 (-6075 4160);
PAINT MONO (-6075 4160);
DISPLAY INVISIBLE (-6075 4160);
WIRE 16 -1 (-5450 4100)(-5450 4150);
WIRE 16 -1 (-5450 4150)(-5000 4150);
WIRE 16 -1 (-5000 4100)(-5000 4150);
WIRE 16 -1 (-4650 4150)(-4650 3525);
WIRE 16 -1 (-4650 4150)(-5000 4150);
WIRE 16 2175 (-4325 3850)(-4325 4225);
WIRE 16 2175 (-3100 3850)(-4325 3850);
WIRE 16 2175 (-4325 4225)(-3100 4225);
WIRE 16 2175 (-3100 4225)(-3100 3850);
WIRE 16 2175 (-5100 3650)(-7400 3650);
WIRE 16 2175 (-5100 4250)(-5100 3650);
WIRE 16 2175 (-7400 3650)(-7400 4250);
WIRE 16 2175 (-7400 4250)(-5100 4250);
WIRE 16 -1 (-5000 2575)(-5000 2125);
FORCEPROP 2 LAST SIG_NAME VR_PVPP_GHJ_SS
R 1
J 0
(-5010 2135);
DISPLAY 0.617021 (-5010 2135);
PAINT ORANGE (-5010 2135);
FORCEPROP 2 LASTPROP $XRERR UNIQUE?
J 0
(-5250 2135);
DISPLAY 0.638298 (-5250 2135);
PAINT MONO (-5250 2135);
DISPLAY INVISIBLE (-5250 2135);
WIRE 16 -1 (-4225 2575)(-5000 2575);
WIRE 16 -1 (-2100 2300)(-2675 2300);
FORCEPROP 0 LAST SIG_NAME VR_COMP_RC_PVPP_GHJ
J 0
(-2610 2310);
DISPLAY 0.617021 (-2610 2310);
PAINT ORANGE (-2610 2310);
FORCEPROP 2 LASTPROP $XRERR UNIQUE?
J 0
(-2850 2310);
DISPLAY 0.638298 (-2850 2310);
PAINT MONO (-2850 2310);
DISPLAY INVISIBLE (-2850 2310);
WIRE 16 -1 (-2450 3200)(-2450 3375);
FORCEPROP 2 LAST SIG_NAME VR_PVPP_GHJ_SNUB
J 0
(-2435 3235);
DISPLAY 0.617021 (-2435 3235);
PAINT ORANGE (-2435 3235);
FORCEPROP 2 LASTPROP $XRERR UNIQUE?
J 0
(-2675 3235);
DISPLAY 0.638298 (-2675 3235);
PAINT MONO (-2675 3235);
DISPLAY INVISIBLE (-2675 3235);
WIRE 16 -1 (-6500 2300)(-6500 2675);
WIRE 16 -1 (-6500 2675)(-6175 2675);
WIRE 16 -1 (-7100 2300)(-7100 2675);
WIRE 16 -1 (-7100 2675)(-6500 2675);
WIRE 16 -1 (-7525 2675)(-7100 2675);
FORCEPROP 2 LAST SIG_NAME FM_PVPP_CPU1_EN
J 0
(-7501 2700);
DISPLAY 0.617021 (-7501 2700);
PAINT ORANGE (-7501 2700);
WIRE 16 -1 (-3400 4050)(-3975 4050);
FORCEPROP 2 LAST SIG_NAME VR_PVPP_GHJ_BOOT_R
J 0
(-3905 4060);
DISPLAY 0.617021 (-3905 4060);
PAINT ORANGE (-3905 4060);
FORCEPROP 2 LASTPROP $XRERR UNIQUE?
J 0
(-4145 4060);
DISPLAY 0.638298 (-4145 4060);
PAINT MONO (-4145 4060);
DISPLAY INVISIBLE (-4145 4060);
WIRE 16 -1 (-3225 2875)(-2950 2875);
WIRE 16 -1 (-3225 2975)(-2950 2975);
WIRE 16 -1 (-2950 2875)(-2950 2975);
WIRE 16 -1 (-3225 3025)(-2950 3025);
WIRE 16 -1 (-2950 2975)(-2950 3025);
WIRE 16 -1 (-3225 3075)(-2950 3075);
WIRE 16 -1 (-2950 3025)(-2950 3075);
WIRE 16 -1 (-3225 3125)(-2950 3125);
WIRE 16 -1 (-2950 3075)(-2950 3125);
WIRE 16 -1 (-3225 3175)(-2950 3175);
WIRE 16 -1 (-2950 3125)(-2950 3175);
WIRE 16 -1 (-3225 3225)(-2950 3225);
WIRE 16 -1 (-2950 3175)(-2950 3225);
WIRE 16 -1 (-3225 3275)(-2950 3275);
WIRE 16 -1 (-2950 3225)(-2950 3275);
WIRE 16 -1 (-3200 4050)(-2950 4050);
WIRE 16 -1 (-3225 3325)(-2950 3325);
WIRE 16 -1 (-2950 3275)(-2950 3325);
WIRE 16 -1 (-2450 3575)(-2450 3700);
WIRE 16 -1 (-2275 3700)(-2450 3700);
WIRE 16 -1 (-2950 3325)(-2950 3700);
WIRE 16 -1 (-2950 4050)(-2950 3700);
WIRE 16 -1 (-2950 3700)(-2450 3700);
FORCEPROP 2 LAST SIG_NAME VR_PVPP_GHJ_PHASE
J 0
(-2910 3710);
DISPLAY 0.617021 (-2910 3710);
PAINT ORANGE (-2910 3710);
FORCEPROP 2 LASTPROP $XRERR UNIQUE?
J 0
(-3150 3710);
DISPLAY 0.638298 (-3150 3710);
PAINT MONO (-3150 3710);
DISPLAY INVISIBLE (-3150 3710);
WIRE 16 -1 (-3175 3425)(-3225 3425);
WIRE 16 -1 (-3175 3750)(-3175 3425);
WIRE 16 -1 (-4225 3750)(-3175 3750);
WIRE 16 -1 (-4225 4050)(-4225 3750);
FORCEPROP 2 LAST SIG_NAME VR_PVPP_GHJ_BOOT
J 0
(-4135 3785);
DISPLAY 0.617021 (-4135 3785);
PAINT ORANGE (-4135 3785);
FORCEPROP 2 LASTPROP $XRERR UNIQUE?
J 0
(-4375 3785);
DISPLAY 0.638298 (-4375 3785);
PAINT MONO (-4375 3785);
DISPLAY INVISIBLE (-4375 3785);
WIRE 16 -1 (-4175 4050)(-4225 4050);
WIRE 3 682 (-4275 4150)(-4275 3875);
WIRE 3 682 (-3950 4150)(-4275 4150);
WIRE 3 682 (-4275 3875)(-3950 3875);
WIRE 3 682 (-3950 3875)(-3950 4150);
WIRE 16 682 (-1925 4600)(-1925 4100);
WIRE 16 682 (-650 4600)(-1925 4600);
WIRE 16 682 (-1925 4100)(-650 4100);
WIRE 16 682 (-650 4100)(-650 4600);
WIRE 16 -1 (-950 2575)(-950 2650);
WIRE 16 -1 (-1275 2650)(-1275 2800);
WIRE 16 -1 (-950 2650)(-1275 2650);
WIRE 16 -1 (-1275 1900)(-1275 2650);
FORCEPROP 0 LAST SIG_NAME VSENSE_PVPP_GHJ
R 1
J 0
(-1285 1935);
DISPLAY 0.617021 (-1285 1935);
PAINT ORANGE (-1285 1935);
FORCEPROP 2 LASTPROP $XRERR UNIQUE?
J 0
(-1525 1935);
DISPLAY 0.638298 (-1525 1935);
PAINT MONO (-1525 1935);
DISPLAY INVISIBLE (-1525 1935);
WIRE 16 -1 (-950 1800)(-950 2375);
FORCEPROP 0 LAST SIG_NAME VR_COMP_PVPP_GHJ
R 1
J 0
(-960 1885);
DISPLAY 0.617021 (-960 1885);
PAINT ORANGE (-960 1885);
FORCEPROP 2 LASTPROP $XRERR UNIQUE?
J 0
(-1200 1885);
DISPLAY 0.638298 (-1200 1885);
PAINT MONO (-1200 1885);
DISPLAY INVISIBLE (-1200 1885);
WIRE 16 -1 (-3225 2675)(-2925 2675);
WIRE 16 -1 (-2925 2675)(-2250 2675);
WIRE 16 -1 (-2875 2300)(-2925 2300);
WIRE 16 -1 (-2925 2300)(-2925 2675);
FORCEPROP 0 LAST SIG_NAME VR_COMP_PVPP_GHJ_3
J 0
(-2835 2685);
DISPLAY 0.617021 (-2835 2685);
PAINT ORANGE (-2835 2685);
FORCEPROP 2 LASTPROP $XRERR UNIQUE?
J 0
(-3075 2685);
DISPLAY 0.638298 (-3075 2685);
PAINT MONO (-3075 2685);
DISPLAY INVISIBLE (-3075 2685);
WIRE 16 -1 (-5800 2875)(-4225 2875);
FORCEPROP 0 LAST SIG_NAME VR_VB_PVPP_GHJ
J 0
(-5510 2885);
DISPLAY 0.617021 (-5510 2885);
PAINT ORANGE (-5510 2885);
FORCEPROP 2 LASTPROP $XRERR UNIQUE?
J 0
(-5750 2885);
DISPLAY 0.638298 (-5750 2885);
PAINT MONO (-5750 2885);
DISPLAY INVISIBLE (-5750 2885);
WIRE 16 -1 (-5800 2450)(-5800 2875);
WIRE 3 682 (-5950 2025)(-5400 2025);
WIRE 3 682 (-5950 2500)(-5950 2025);
WIRE 3 682 (-5400 2025)(-5400 2500);
WIRE 3 682 (-5400 2500)(-5950 2500);
WIRE 16 -1 (-950 1600)(-950 1550);
WIRE 16 -1 (-1850 2300)(-1900 2300);
WIRE 16 -1 (-2050 2675)(-1850 2675);
WIRE 16 -1 (-1850 2300)(-1850 2675);
WIRE 16 -1 (-1275 1700)(-1275 1550);
WIRE 16 -1 (-950 1550)(-1275 1550);
WIRE 16 -1 (-1275 1475)(-1275 1325);
WIRE 16 -1 (-1275 1550)(-1275 1475);
WIRE 16 -1 (-3225 2775)(-1850 2775);
WIRE 16 -1 (-1850 2675)(-1850 2775);
WIRE 16 -1 (-1800 2775)(-1850 2775);
WIRE 16 -1 (-1800 1475)(-1275 1475);
FORCEPROP 0 LAST SIG_NAME VR_FB_PVPP_GHJ
J 0
(-1760 1485);
DISPLAY 0.617021 (-1760 1485);
PAINT ORANGE (-1760 1485);
FORCEPROP 2 LASTPROP $XRERR UNIQUE?
J 0
(-2000 1485);
DISPLAY 0.638298 (-2000 1485);
PAINT MONO (-2000 1485);
DISPLAY INVISIBLE (-2000 1485);
WIRE 16 -1 (-1800 1475)(-1800 2775);
WIRE 16 2175 (-700 3150)(-700 975);
WIRE 16 2175 (-1350 3150)(-700 3150);
WIRE 16 2175 (-1350 975)(-700 975);
WIRE 16 2175 (-1350 975)(-1350 3150);
WIRE 3 682 (-1400 1000)(-1400 1400);
WIRE 3 682 (-950 1000)(-1400 1000);
WIRE 3 682 (-1400 1400)(-950 1400);
WIRE 3 682 (-950 1400)(-950 1000);
WIRE 16 -1 (-5975 2675)(-4225 2675);
FORCEPROP 2 LAST SIG_NAME FM_PVPP_PVDDQ_CPU1_EN_GHJ
J 0
(-5151 2700);
DISPLAY 0.617021 (-5151 2700);
PAINT ORANGE (-5151 2700);
FORCEPROP 2 LASTPROP $XRERR UNIQUE?
J 0
(-5391 2700);
DISPLAY 0.638298 (-5391 2700);
PAINT MONO (-5391 2700);
DISPLAY INVISIBLE (-5391 2700);
WIRE 68 -1 (-6700 3700)(-6700 4200);
WIRE 68 -1 (-7350 4200)(-6700 4200);
WIRE 68 -1 (-7350 3700)(-6700 3700);
WIRE 68 -1 (-7350 3700)(-7350 4200);
WIRE 16 -1 (-2600 825)(-3275 825);
FORCEPROP 2 LAST SIG_NAME PWRGD_PVPP_GHJ
J 0
(-2985 835);
DISPLAY 0.617021 (-2985 835);
PAINT ORANGE (-2985 835);
WIRE 16 -1 (-4675 2475)(-4225 2475);
WIRE 16 -1 (-4675 1600)(-4675 2475);
FORCEPROP 2 LAST SIG_NAME VR_PVPP_GHJ_ISET
R 1
J 0
(-4685 1960);
DISPLAY 0.617021 (-4685 1960);
PAINT ORANGE (-4685 1960);
FORCEPROP 2 LASTPROP $XRERR UNIQUE?
J 0
(-4925 1960);
DISPLAY 0.638298 (-4925 1960);
PAINT MONO (-4925 1960);
DISPLAY INVISIBLE (-4925 1960);
WIRE 16 -1 (-3800 675)(-3800 825);
WIRE 16 -1 (-3475 825)(-3800 825);
FORCEPROP 2 LAST SIG_NAME PWRGD_PVPP_GHJ_R
J 0
(-4035 835);
DISPLAY 0.617021 (-4035 835);
PAINT ORANGE (-4035 835);
FORCEPROP 2 LASTPROP $XRERR UNIQUE?
J 0
(-4275 835);
DISPLAY 0.638298 (-4275 835);
PAINT MONO (-4275 835);
DISPLAY INVISIBLE (-4275 835);
WIRE 16 -1 (-4150 1000)(-4150 825);
WIRE 16 -1 (-3800 825)(-4150 825);
WIRE 16 -1 (-4225 2375)(-4475 2375);
WIRE 16 -1 (-4150 825)(-4475 825);
WIRE 16 -1 (-4475 825)(-4475 2375);
WIRE 3 682 (-5200 1700)(-5200 1150);
WIRE 3 682 (-4550 1700)(-5200 1700);
WIRE 3 682 (-5200 1150)(-4550 1150);
WIRE 3 682 (-4550 1150)(-4550 1700);
DOT 1 (-1400 3700);
DOT 1 (-1700 3700);
DOT 1 (-7300 4150);
DOT 1 (-7000 4150);
DOT 1 (-6600 4150);
DOT 1 (-5450 4150);
DOT 1 (-5875 4150);
DOT 1 (-4650 3425);
DOT 1 (-2925 2675);
DOT 1 (-3000 2125);
DOT 1 (-6250 4150);
DOT 1 (-7100 2675);
DOT 1 (-5000 4150);
DOT 1 (-4650 3275);
DOT 1 (-2450 3700);
DOT 1 (-1850 2675);
DOT 1 (-1850 2775);
DOT 1 (-1275 1475);
DOT 1 (-5325 900);
DOT 1 (-6175 900);
DOT 1 (-5875 900);
DOT 1 (-725 3700);
DOT 1 (-775 3700);
DOT 1 (-1075 3700);
DOT 1 (-2000 3700);
DOT 1 (-1275 2650);
DOT 1 (-2950 3700);
DOT 1 (-2950 3225);
DOT 1 (-2950 3325);
DOT 1 (-2950 3275);
DOT 1 (-2950 3125);
DOT 1 (-2950 3175);
DOT 1 (-2950 3075);
DOT 1 (-2950 2975);
DOT 1 (-2950 3025);
DOT 1 (-3000 2525);
DOT 1 (-3000 2475);
DOT 1 (-3000 2375);
DOT 1 (-3000 2325);
DOT 1 (-3000 2425);
DOT 1 (-3000 2225);
DOT 1 (-3000 2275);
DOT 1 (-3000 2075);
DOT 1 (-3000 2175);
DOT 1 (-3000 1975);
DOT 1 (-3000 2025);
DOT 1 (-3000 1925);
DOT 1 (-3000 1875);
DOT 1 (-3800 825);
DOT 1 (-4650 3525);
DOT 1 (-4650 3325);
DOT 1 (-4650 3225);
DOT 1 (-4650 3175);
DOT 1 (-4650 3125);
DOT 1 (-4650 3075);
DOT 1 (-4650 3025);
DOT 1 (-4150 825);
DOT 1 (-5600 900);
DOT 1 (-6500 2675);
DOT 1 (-6475 900);
DOT 1 (-6750 900);
DOT 1 (-7050 900);
DOT 1 (-7325 900);
DOT 1 (-8100 900);
DOT 1 (-7875 900);
DOT 1 (-7600 900);
DOT 1 (-1275 1550);
DOT 1 (-8150 350);
DOT 1 (-7325 350);
DOT 1 (-6750 350);
DOT 1 (-6475 350);
DOT 1 (-6175 350);
DOT 1 (-5875 350);
DOT 1 (-5600 350);
DOT 1 (-5325 350);
DOT 1 (-7600 350);
DOT 1 (-7875 350);
DOT 1 (-7050 350);
FORCENOTE
PUT TOGETHER
(-7350 4200) 0;
DISPLAY LEFT (-7350 4200);
DISPLAY 0.808511 (-7350 4200);
PAINT PURPLE (-7350 4200);
FORCENOTE
6.25MS
(-5320 2055) 0;
DISPLAY LEFT (-5320 2055);
PAINT PURPLE (-5320 2055);
FORCENOTE
COMPENSATION TYPE III
(-2900 2000) 0;
DISPLAY LEFT (-2900 2000);
DISPLAY 1.042553 (-2900 2000);
PAINT PURPLE (-2900 2000);
FORCENOTE
IOUT DI/DT = 21.5A/US
(-1900 4175) 0;
DISPLAY LEFT (-1900 4175);
DISPLAY 1.021277 (-1900 4175);
PAINT PURPLE (-1900 4175);
FORCENOTE
IOUT STEP = 5.3A
(-1900 4225) 0;
DISPLAY LEFT (-1900 4225);
DISPLAY 1.021277 (-1900 4225);
PAINT PURPLE (-1900 4225);
FORCENOTE
IOUT PK = 10.1A (INCLUDED CPU PVPP)
(-1900 4275) 0;
DISPLAY LEFT (-1900 4275);
DISPLAY 1.021277 (-1900 4275);
PAINT PURPLE (-1900 4275);
FORCENOTE
IOUT TDC = 7.21A (INCLUDED CPU PVPP)
(-1900 4325) 0;
DISPLAY LEFT (-1900 4325);
DISPLAY 1.021277 (-1900 4325);
PAINT PURPLE (-1900 4325);
FORCENOTE
AC & RIPPLE TOL = +3.5%, -7.3%
(-1900 4375) 0;
DISPLAY LEFT (-1900 4375);
DISPLAY 1.021277 (-1900 4375);
PAINT PURPLE (-1900 4375);
FORCENOTE
DC TOL = +/-1.5%
(-1900 4425) 0;
DISPLAY LEFT (-1900 4425);
DISPLAY 1.021277 (-1900 4425);
PAINT PURPLE (-1900 4425);
FORCENOTE
SPOF
(-1105 3000) 0;
DISPLAY LEFT (-1105 3000);
DISPLAY 2.340426 (-1105 3000);
PAINT PURPLE (-1105 3000);
FORCENOTE
(0.4V/MS)
(-5345 1980) 0;
DISPLAY LEFT (-5345 1980);
PAINT PURPLE (-5345 1980);
FORCENOTE
CONNECT AT SINGLE
(-1400 750) 0;
DISPLAY LEFT (-1400 750);
DISPLAY 1.042553 (-1400 750);
PAINT PURPLE (-1400 750);
FORCENOTE
VOUT = 2.5V
(-1900 4525) 0;
DISPLAY LEFT (-1900 4525);
DISPLAY 1.021277 (-1900 4525);
PAINT PURPLE (-1900 4525);
FORCENOTE
BOM_COST: PVPP_GHJ_VR
(-7450 0) 0;
DISPLAY LEFT (-7450 0);
DISPLAY 0.787234 (-7450 0);
PAINT PURPLE (-7450 0);
FORCENOTE
SPOF
(-4325 4275) 0;
DISPLAY LEFT (-4325 4275);
DISPLAY 1.659574 (-4325 4275);
PAINT PURPLE (-4325 4275);
FORCENOTE
TP FAB1 CHANGE RES PACKAGE TO 0603
(-4275 4175) 0;
DISPLAY LEFT (-4275 4175);
DISPLAY 0.638298 (-4275 4175);
PAINT RED (-4275 4175);
FORCENOTE
TOP LAYER
(-3650 4275) 0;
DISPLAY LEFT (-3650 4275);
DISPLAY 1.042553 (-3650 4275);
PAINT PURPLE (-3650 4275);
FORCENOTE
PLACE ON
(-4025 4275) 0;
DISPLAY LEFT (-4025 4275);
DISPLAY 1.042553 (-4025 4275);
PAINT PURPLE (-4025 4275);
FORCENOTE
TP FAB1 CHANGE CAP 0422
(-6000 1925) 0;
DISPLAY LEFT (-6000 1925);
DISPLAY 1.021277 (-6000 1925);
PAINT RED (-6000 1925);
FORCENOTE
TP FAB1 CHANGE RES 0531
(-2300 1000) 0;
DISPLAY LEFT (-2300 1000);
DISPLAY 1.021277 (-2300 1000);
PAINT RED (-2300 1000);
FORCENOTE
TP FAB1 CHANGE ONE 47UF CPA TO TWO 22UF CAPS 0107
(-7775 3575) 0;
DISPLAY LEFT (-7775 3575);
DISPLAY 1.021277 (-7775 3575);
PAINT RED (-7775 3575);
FORCENOTE
TP FAB3 CHANGE CAP 0823
(-5225 1100) 0;
DISPLAY LEFT (-5225 1100);
DISPLAY 0.638298 (-5225 1100);
PAINT RED (-5225 1100);
FORCENOTE
12A OC
(-5145 1580) 0;
DISPLAY LEFT (-5145 1580);
PAINT PURPLE (-5145 1580);
FORCENOTE
ROOM = PVPP_GHJ_VR
(-7450 50) 0;
DISPLAY LEFT (-7450 50);
DISPLAY 0.787234 (-7450 50);
PAINT PURPLE (-7450 50);
FORCENOTE
CAPS TO BE PLACED BETWEEN DIMMS
(-7870 980) 0;
DISPLAY LEFT (-7870 980);
DISPLAY 1.021277 (-7870 980);
PAINT PURPLE (-7870 980);
FORCENOTE
RIPPLE GUIDELINE = +/- 1.0%
(-1900 4475) 0;
DISPLAY LEFT (-1900 4475);
DISPLAY 1.021277 (-1900 4475);
PAINT PURPLE (-1900 4475);
FORCENOTE
POINT ONLY TOP TO L2
(-1450 700) 0;
DISPLAY LEFT (-1450 700);
DISPLAY 1.042553 (-1450 700);
PAINT PURPLE (-1450 700);
FORCENOTE
SW FREQ =  500KHZ
(-1900 4125) 0;
DISPLAY LEFT (-1900 4125);
DISPLAY 1.021277 (-1900 4125);
PAINT PURPLE (-1900 4125);
QUIT
